G04 ================== begin FILE IDENTIFICATION RECORD ==================*
G04 Layout Name:  9049_F0T_FAN_BOARD_MP5048_D_v02_20221209_0830.brd*
G04 Film Name:    ssb.art*
G04 File Format:  Gerber RS274X*
G04 File Origin:  Cadence Allegro 17.2-S081*
G04 Origin Date:  Mon Dec 12 15:05:05 2022*
G04 *
G04 Layer:  DRAWING FORMAT/TITLE_BLOCK_A*
G04 Layer:  BOARD GEOMETRY/DESIGN_OUTLINE*
G04 Layer:  BOARD GEOMETRY/CUTOUT*
G04 Layer:  DRAWING FORMAT/TITLE_BLOCK*
G04 Layer:  MANUFACTURING/TP_TEXT_BOTTOM*
G04 Layer:  REF DES/SILKSCREEN_BOTTOM*
G04 Layer:  PACKAGE GEOMETRY/SILKSCREEN_BOTTOM*
G04 Layer:  MANUFACTURING/PHOTOPLOT_OUTLINE*
G04 Layer:  DRAWING FORMAT/TITLE_DATA_SSB*
G04 Layer:  BOARD GEOMETRY/SILKSCREEN_BOTTOM*
G04 *
G04 Offset:    (0.00 0.00)*
G04 Mirror:    No*
G04 Mode:      Positive*
G04 Rotation:  0*
G04 FullContactRelief:  No*
G04 UndefLineWidth:     6.00*
G04 ================== end FILE IDENTIFICATION RECORD ====================*
%FSLAX25Y25*MOIN*%
%IR0*IPPOS*OFA0.00000B0.00000*MIA0B0*SFA1.00000B1.00000*%
%ADD10C,.006*%
G75*
%LPD*%
G75*
G36*
G01X4615Y46858D02*
Y50858D01*
X8615Y48858D01*
X4615Y46858D01*
G37*
G36*
G01X9572Y272639D02*
X8730Y275166D01*
X7046Y273481D01*
X9572Y272639D01*
G37*
G36*
G01X4615Y410244D02*
Y414244D01*
X8615Y412244D01*
X4615Y410244D01*
G37*
G36*
G01Y773630D02*
Y777630D01*
X8615Y775630D01*
X4615Y773630D01*
G37*
G36*
G01X9926Y1000583D02*
X9083Y1003109D01*
X7399Y1001425D01*
X9926Y1000583D01*
G37*
G36*
G01X4615Y1137016D02*
Y1141016D01*
X8615Y1139016D01*
X4615Y1137016D01*
G37*
G36*
G01X24141Y262569D02*
X21841Y263469D01*
Y261769D01*
X24141Y262569D01*
G37*
G36*
G01X33385Y330428D02*
X8785D01*
Y326728D01*
X33385D01*
Y330428D01*
G37*
G36*
G01X24141Y989841D02*
X21841Y990741D01*
Y989041D01*
X24141Y989841D01*
G37*
G36*
G01X33885Y1057200D02*
X9285D01*
Y1053500D01*
X33885D01*
Y1057200D01*
G37*
G36*
G01X36965Y238071D02*
X34800Y236988D01*
X36965Y235906D01*
Y238071D01*
G37*
G36*
G01X45967Y231028D02*
X70567D01*
Y234728D01*
X45967D01*
Y231028D01*
G37*
G36*
G01X42000Y308192D02*
X44552Y309468D01*
X42000Y310744D01*
Y308192D01*
G37*
G36*
G01X37100Y964910D02*
X34800Y963760D01*
X37100Y962610D01*
Y964910D01*
G37*
G36*
G01X47167Y955200D02*
X71767D01*
Y958900D01*
X47167D01*
Y955200D01*
G37*
G36*
G01X42586Y1035007D02*
X45052Y1036240D01*
X42586Y1037472D01*
Y1035007D01*
G37*
G36*
G01X55211Y283387D02*
X57511Y282487D01*
Y284187D01*
X55211Y283387D01*
G37*
G36*
G01X69555Y274531D02*
X68364Y272149D01*
X70746D01*
X69555Y274531D01*
G37*
G36*
G01X55711Y1010159D02*
X58011Y1009259D01*
Y1010959D01*
X55711Y1010159D01*
G37*
G36*
G01X70055Y1001303D02*
X68864Y998921D01*
X71246D01*
X70055Y1001303D01*
G37*
G36*
G01X142682Y330428D02*
X118082D01*
Y326728D01*
X142682D01*
Y330428D01*
G37*
G36*
G01Y1057200D02*
X118082D01*
Y1053500D01*
X142682D01*
Y1057200D01*
G37*
G36*
G01X147832Y263069D02*
X145532Y263969D01*
Y262269D01*
X147832Y263069D01*
G37*
G36*
G01X133488Y271925D02*
X134679Y274307D01*
X132297D01*
X133488Y271925D01*
G37*
G36*
G01X147832Y992990D02*
X145532Y993890D01*
Y992190D01*
X147832Y992990D01*
G37*
G36*
G01X133488Y1001846D02*
X134679Y1004228D01*
X132297D01*
X133488Y1001846D01*
G37*
G36*
G01X161520Y238503D02*
X158491Y236988D01*
X161520Y235474D01*
Y238503D01*
G37*
G36*
G01X164508Y283387D02*
X166808Y282487D01*
Y284187D01*
X164508Y283387D01*
G37*
G36*
G01X151517Y308302D02*
X153849Y309468D01*
X151517Y310634D01*
Y308302D01*
G37*
G36*
G01X161520Y968424D02*
X158491Y966909D01*
X161520Y965395D01*
Y968424D01*
G37*
G36*
G01X164508Y1010159D02*
X166808Y1009259D01*
Y1010959D01*
X164508Y1010159D01*
G37*
G36*
G01X151500Y1035065D02*
X153849Y1036240D01*
X151500Y1037414D01*
Y1035065D01*
G37*
G36*
G01X170758Y228428D02*
X195358D01*
Y232128D01*
X170758D01*
Y228428D01*
G37*
G36*
G01X178852Y274531D02*
X177661Y272149D01*
X180043D01*
X178852Y274531D01*
G37*
G36*
G01X171600Y954000D02*
X196200D01*
Y957700D01*
X171600D01*
Y954000D01*
G37*
G36*
G01X178852Y1001303D02*
X177661Y998921D01*
X180043D01*
X178852Y1001303D01*
G37*
G36*
G01X198928Y105976D02*
Y101976D01*
X194928Y103976D01*
X198928Y105976D01*
G37*
G36*
G01Y469362D02*
Y465362D01*
X194928Y467362D01*
X198928Y469362D01*
G37*
G36*
G01Y832748D02*
Y828748D01*
X194928Y830748D01*
X198928Y832748D01*
G37*
G36*
G01Y1196134D02*
Y1192134D01*
X194928Y1194134D01*
X198928Y1196134D01*
G37*
G54D10*
G01X-320500Y-470483D02*
Y2626000D01*
X2967000D01*
Y-470483D01*
X-320500D01*
G01X138740Y5906D02*
X144646Y0D01*
X187795D01*
G03X203543Y15748I0J15748D01*
G01Y1311024D01*
G03X187795Y1326772I-15748J0D01*
G01X15748D01*
G03X0Y1311024I0J-15748D01*
G01Y15748D01*
G03X15748Y0I15748J0D01*
G01X58898D01*
X64803Y5906D01*
Y43307D01*
G02X74252I4724J0D01*
G01Y7283D01*
X80157Y1378D01*
X99488D01*
X105394Y7283D01*
Y43307D01*
G02X108150I1378J0D01*
G01Y7283D01*
X114055Y1378D01*
X123386D01*
X129291Y7283D01*
Y43307D01*
G02X138740I4724J0D01*
G01Y5906D01*
G01X27362Y41378D02*
G02X33268I2953J0D01*
G02X27362I-2953J0D01*
G01Y404764D02*
G02X33268I2953J0D01*
G02X27362I-2953J0D01*
G01Y768150D02*
G02X33268I2953J0D01*
G02X27362I-2953J0D01*
G01Y1131535D02*
G02X33268I2953J0D01*
G02X27362I-2953J0D01*
G01X32908Y574289D02*
X36832Y621205D01*
G02X48601I5885J-492D01*
G01X52525Y574289D01*
G02X32908I-9808J-820D01*
G01X91929Y157126D02*
X95886Y204858D01*
G02X107657I5886J-488D01*
G01X111614Y157126D01*
G02X91929I-9842J0D01*
G01Y905157D02*
X95886Y952889D01*
G02X107657I5886J-488D01*
G01X111614Y905157D01*
G02X91929I-9842J0D01*
G01X89173Y1287047D02*
G02X114370I12599J0D01*
G02X89173I-12599J0D01*
G01X151019Y574289D02*
X154942Y621205D01*
G02X166712I5885J-492D01*
G01X170635Y574289D01*
G02X151019I-9808J-820D01*
G01X170276Y111457D02*
G02X176181I2953J0D01*
G02X170276I-2952J0D01*
G01Y474843D02*
G02X176181I2953J0D01*
G02X170276I-2952J0D01*
G01Y838228D02*
G02X176181I2953J0D01*
G02X170276I-2952J0D01*
G01Y1201614D02*
G02X176181I2953J0D01*
G02X170276I-2952J0D01*
G01X329322Y-314459D02*
Y-319459D01*
G01X327865Y-314459D02*
X330779D01*
G01X335689Y-319459D02*
X333155D01*
Y-314459D01*
X335689D01*
G01X334675Y-316876D02*
X333155D01*
G01X338255Y-314459D02*
Y-319459D01*
X340789D01*
G01X344622Y-319626D02*
X344495Y-319542D01*
Y-319376D01*
X344622Y-319292D01*
X344749Y-319376D01*
Y-319542D01*
X344622Y-319626D01*
G01Y-317376D02*
X344495Y-317292D01*
Y-317126D01*
X344622Y-317042D01*
X344749Y-317126D01*
Y-317292D01*
X344622Y-317376D01*
G01X349405Y-321126D02*
X348772Y-320292D01*
X348455Y-319459D01*
Y-316126D01*
X348772Y-315292D01*
X349405Y-314459D01*
G01X354822D02*
X354315Y-314626D01*
X353935Y-315042D01*
X353682Y-315542D01*
X353492Y-316209D01*
X353429Y-316959D01*
X353492Y-317709D01*
X353682Y-318376D01*
X353935Y-318876D01*
X354315Y-319292D01*
X354822Y-319459D01*
X355329Y-319292D01*
X355709Y-318876D01*
X355962Y-318376D01*
X356152Y-317709D01*
X356215Y-316959D01*
X356152Y-316209D01*
X355962Y-315542D01*
X355709Y-315042D01*
X355329Y-314626D01*
X354822Y-314459D01*
G01X358529Y-318459D02*
X358909Y-319042D01*
X359415Y-319376D01*
X359985Y-319459D01*
X360492Y-319376D01*
X360999Y-318959D01*
X361315Y-318459D01*
X361379Y-317959D01*
X361252Y-317376D01*
X360809Y-316959D01*
X360365Y-316792D01*
X359795D01*
G01X360365D02*
X360745Y-316542D01*
X361062Y-316126D01*
X361189Y-315626D01*
X361062Y-315126D01*
X360745Y-314709D01*
X360175Y-314459D01*
X359605Y-314542D01*
X359035Y-314876D01*
G01X365339Y-321126D02*
X365972Y-320292D01*
X366289Y-319459D01*
Y-316126D01*
X365972Y-315292D01*
X365339Y-314459D01*
G01X368729Y-318459D02*
X369109Y-319042D01*
X369615Y-319376D01*
X370185Y-319459D01*
X370692Y-319376D01*
X371199Y-318959D01*
X371515Y-318459D01*
X371579Y-317959D01*
X371452Y-317376D01*
X371009Y-316959D01*
X370565Y-316792D01*
X369995D01*
G01X370565D02*
X370945Y-316542D01*
X371262Y-316126D01*
X371389Y-315626D01*
X371262Y-315126D01*
X370945Y-314709D01*
X370375Y-314459D01*
X369805Y-314542D01*
X369235Y-314876D01*
G01X374019Y-315292D02*
X374399Y-314792D01*
X374842Y-314542D01*
X375349Y-314459D01*
X375982Y-314626D01*
X376425Y-315042D01*
X376552Y-315542D01*
X376489Y-316042D01*
X376235Y-316459D01*
X374969Y-317292D01*
X374399Y-317876D01*
X374019Y-318709D01*
X373892Y-319459D01*
X376552D01*
G01X380195D02*
X380322Y-318376D01*
X380512Y-317459D01*
X380765Y-316626D01*
X381082Y-315709D01*
X381589Y-314459D01*
X379055D01*
G01X384599Y-317792D02*
X386245D01*
G01X389319Y-315292D02*
X389699Y-314792D01*
X390142Y-314542D01*
X390649Y-314459D01*
X391282Y-314626D01*
X391725Y-315042D01*
X391852Y-315542D01*
X391789Y-316042D01*
X391535Y-316459D01*
X390269Y-317292D01*
X389699Y-317876D01*
X389319Y-318709D01*
X389192Y-319459D01*
X391852D01*
G01X394229Y-318459D02*
X394609Y-319042D01*
X395115Y-319376D01*
X395685Y-319459D01*
X396192Y-319376D01*
X396699Y-318959D01*
X397015Y-318459D01*
X397079Y-317959D01*
X396952Y-317376D01*
X396509Y-316959D01*
X396065Y-316792D01*
X395495D01*
G01X396065D02*
X396445Y-316542D01*
X396762Y-316126D01*
X396889Y-315626D01*
X396762Y-315126D01*
X396445Y-314709D01*
X395875Y-314459D01*
X395305Y-314542D01*
X394735Y-314876D01*
G01X401482Y-319459D02*
Y-314459D01*
X399139Y-318042D01*
X402305D01*
G01X404429Y-318709D02*
X404809Y-319126D01*
X405252Y-319376D01*
X405822Y-319459D01*
X406392Y-319292D01*
X406835Y-318959D01*
X407152Y-318376D01*
X407215Y-317709D01*
X407089Y-317042D01*
X406772Y-316626D01*
X406329Y-316292D01*
X405885Y-316209D01*
X405442Y-316292D01*
X404872Y-316626D01*
X405062Y-314459D01*
X406772D01*
G01X414819Y-319459D02*
Y-314459D01*
X417225D01*
G01X416339Y-316876D02*
X414819D01*
G01X419539Y-319459D02*
X421122Y-314459D01*
X422705Y-319459D01*
G01X422135Y-317709D02*
X420109D01*
G01X424892Y-319459D02*
X427552Y-314459D01*
G01X424892D02*
X427552Y-319459D01*
G01X431322Y-319626D02*
X431195Y-319542D01*
Y-319376D01*
X431322Y-319292D01*
X431449Y-319376D01*
Y-319542D01*
X431322Y-319626D01*
G01Y-317376D02*
X431195Y-317292D01*
Y-317126D01*
X431322Y-317042D01*
X431449Y-317126D01*
Y-317292D01*
X431322Y-317376D01*
G01X436105Y-321126D02*
X435472Y-320292D01*
X435155Y-319459D01*
Y-316126D01*
X435472Y-315292D01*
X436105Y-314459D01*
G01X441522D02*
X441015Y-314626D01*
X440635Y-315042D01*
X440382Y-315542D01*
X440192Y-316209D01*
X440129Y-316959D01*
X440192Y-317709D01*
X440382Y-318376D01*
X440635Y-318876D01*
X441015Y-319292D01*
X441522Y-319459D01*
X442029Y-319292D01*
X442409Y-318876D01*
X442662Y-318376D01*
X442852Y-317709D01*
X442915Y-316959D01*
X442852Y-316209D01*
X442662Y-315542D01*
X442409Y-315042D01*
X442029Y-314626D01*
X441522Y-314459D01*
G01X445229Y-318459D02*
X445609Y-319042D01*
X446115Y-319376D01*
X446685Y-319459D01*
X447192Y-319376D01*
X447699Y-318959D01*
X448015Y-318459D01*
X448079Y-317959D01*
X447952Y-317376D01*
X447509Y-316959D01*
X447065Y-316792D01*
X446495D01*
G01X447065D02*
X447445Y-316542D01*
X447762Y-316126D01*
X447889Y-315626D01*
X447762Y-315126D01*
X447445Y-314709D01*
X446875Y-314459D01*
X446305Y-314542D01*
X445735Y-314876D01*
G01X452039Y-321126D02*
X452672Y-320292D01*
X452989Y-319459D01*
Y-316126D01*
X452672Y-315292D01*
X452039Y-314459D01*
G01X455429Y-318459D02*
X455809Y-319042D01*
X456315Y-319376D01*
X456885Y-319459D01*
X457392Y-319376D01*
X457899Y-318959D01*
X458215Y-318459D01*
X458279Y-317959D01*
X458152Y-317376D01*
X457709Y-316959D01*
X457265Y-316792D01*
X456695D01*
G01X457265D02*
X457645Y-316542D01*
X457962Y-316126D01*
X458089Y-315626D01*
X457962Y-315126D01*
X457645Y-314709D01*
X457075Y-314459D01*
X456505Y-314542D01*
X455935Y-314876D01*
G01X460845Y-318876D02*
X461289Y-319292D01*
X461795Y-319459D01*
X462302Y-319292D01*
X462745Y-318792D01*
X463062Y-318042D01*
X463189Y-317292D01*
Y-316376D01*
X463062Y-315626D01*
X462745Y-314959D01*
X462365Y-314626D01*
X461922Y-314459D01*
X461415Y-314626D01*
X461035Y-314959D01*
X460782Y-315459D01*
X460655Y-316126D01*
X460782Y-316709D01*
X461099Y-317292D01*
X461479Y-317626D01*
X461922Y-317709D01*
X462429Y-317542D01*
X462809Y-317126D01*
X463189Y-316376D01*
G01X466895Y-319459D02*
X467022Y-318376D01*
X467212Y-317459D01*
X467465Y-316626D01*
X467782Y-315709D01*
X468289Y-314459D01*
X465755D01*
G01X471299Y-317792D02*
X472945D01*
G01X475829Y-318459D02*
X476209Y-319042D01*
X476715Y-319376D01*
X477285Y-319459D01*
X477792Y-319376D01*
X478299Y-318959D01*
X478615Y-318459D01*
X478679Y-317959D01*
X478552Y-317376D01*
X478109Y-316959D01*
X477665Y-316792D01*
X477095D01*
G01X477665D02*
X478045Y-316542D01*
X478362Y-316126D01*
X478489Y-315626D01*
X478362Y-315126D01*
X478045Y-314709D01*
X477475Y-314459D01*
X476905Y-314542D01*
X476335Y-314876D01*
G01X481119Y-317376D02*
X481562Y-316792D01*
X481942Y-316459D01*
X482449Y-316292D01*
X482892Y-316459D01*
X483209Y-316792D01*
X483462Y-317292D01*
X483525Y-317876D01*
X483462Y-318376D01*
X483209Y-318876D01*
X482829Y-319292D01*
X482385Y-319459D01*
X481879Y-319292D01*
X481435Y-318792D01*
X481182Y-318042D01*
X481119Y-317209D01*
X481245Y-316126D01*
X481435Y-315542D01*
X481752Y-314959D01*
X482195Y-314542D01*
X482639Y-314459D01*
X483082Y-314626D01*
X483399Y-315042D01*
G01X487422Y-319459D02*
Y-314459D01*
X486662Y-315459D01*
G01Y-319459D02*
X488182D01*
G01X493282D02*
Y-314459D01*
X490939Y-318042D01*
X494105D01*
G01X317322Y-249459D02*
Y-324459D01*
X817322D01*
Y-249459D01*
X317322D01*
G01X512322D02*
Y-324459D01*
G01Y-299459D02*
X615322D01*
Y-274459D01*
G01X512322D02*
X615322D01*
G01X622829Y-309459D02*
Y-304459D01*
X624095D01*
X624602Y-304709D01*
X624982Y-305042D01*
X625299Y-305542D01*
X625552Y-306126D01*
X625615Y-306959D01*
X625552Y-307792D01*
X625299Y-308376D01*
X624982Y-308876D01*
X624602Y-309209D01*
X624095Y-309459D01*
X622829D01*
G01X627739D02*
X629322Y-304459D01*
X630905Y-309459D01*
G01X630335Y-307709D02*
X628309D01*
G01X634422Y-304459D02*
Y-309459D01*
G01X632965Y-304459D02*
X635879D01*
G01X640789Y-309459D02*
X638255D01*
Y-304459D01*
X640789D01*
G01X639775Y-306876D02*
X638255D01*
G01X644622Y-309626D02*
X644495Y-309542D01*
Y-309376D01*
X644622Y-309292D01*
X644749Y-309376D01*
Y-309542D01*
X644622Y-309626D01*
G01Y-307376D02*
X644495Y-307292D01*
Y-307126D01*
X644622Y-307042D01*
X644749Y-307126D01*
Y-307292D01*
X644622Y-307376D01*
G01X617322Y-249459D02*
Y-324459D01*
G01X615322Y-249459D02*
Y-324459D01*
G01X622955Y-284459D02*
Y-279459D01*
X624475D01*
X624982Y-279709D01*
X625362Y-280292D01*
X625489Y-280959D01*
X625362Y-281626D01*
X625045Y-282126D01*
X624475Y-282376D01*
X622955D01*
G01X628182Y-284626D02*
X630462Y-279459D01*
G01X632965Y-284459D02*
Y-279459D01*
X635879Y-284459D01*
Y-279459D01*
G01X639522Y-284626D02*
X639395Y-284542D01*
Y-284376D01*
X639522Y-284292D01*
X639649Y-284376D01*
Y-284542D01*
X639522Y-284626D01*
G01Y-282376D02*
X639395Y-282292D01*
Y-282126D01*
X639522Y-282042D01*
X639649Y-282126D01*
Y-282292D01*
X639522Y-282376D01*
G01X617322Y-299459D02*
X817322D01*
G01X622955Y-259459D02*
Y-254459D01*
X624475D01*
X624982Y-254709D01*
X625362Y-255292D01*
X625489Y-255959D01*
X625362Y-256626D01*
X625045Y-257126D01*
X624475Y-257376D01*
X622955D01*
G01X628055Y-259459D02*
Y-254459D01*
X629639D01*
X630145Y-254709D01*
X630462Y-255042D01*
X630589Y-255709D01*
X630462Y-256376D01*
X630082Y-256792D01*
X629639Y-257042D01*
X628055D01*
G01X629639D02*
X630589Y-259459D01*
G01X634422D02*
X633915Y-259376D01*
X633472Y-259042D01*
X633092Y-258542D01*
X632839Y-257959D01*
X632712Y-257292D01*
Y-256626D01*
X632839Y-255959D01*
X633092Y-255376D01*
X633472Y-254876D01*
X633915Y-254542D01*
X634422Y-254459D01*
X634929Y-254542D01*
X635372Y-254876D01*
X635752Y-255376D01*
X636005Y-255959D01*
X636132Y-256626D01*
Y-257292D01*
X636005Y-257959D01*
X635752Y-258542D01*
X635372Y-259042D01*
X634929Y-259376D01*
X634422Y-259459D01*
G01X638255Y-258459D02*
X638572Y-258959D01*
X638952Y-259292D01*
X639395Y-259459D01*
X639902Y-259292D01*
X640282Y-258959D01*
X640662Y-258459D01*
X640789Y-257792D01*
Y-254459D01*
G01X645889Y-259459D02*
X643355D01*
Y-254459D01*
X645889D01*
G01X644875Y-256876D02*
X643355D01*
G01X651115Y-254876D02*
X650735Y-254626D01*
X650292Y-254459D01*
X649785D01*
X649215Y-254709D01*
X648772Y-255126D01*
X648455Y-255626D01*
X648202Y-256459D01*
X648139Y-257209D01*
X648265Y-257959D01*
X648455Y-258459D01*
X648835Y-258959D01*
X649279Y-259292D01*
X649722Y-259459D01*
X650165D01*
X650609Y-259292D01*
X650989Y-259042D01*
X651305Y-258709D01*
G01X654822Y-254459D02*
Y-259459D01*
G01X653365Y-254459D02*
X656279D01*
G01X659922Y-259626D02*
X659795Y-259542D01*
Y-259376D01*
X659922Y-259292D01*
X660049Y-259376D01*
Y-259542D01*
X659922Y-259626D01*
G01Y-257376D02*
X659795Y-257292D01*
Y-257126D01*
X659922Y-257042D01*
X660049Y-257126D01*
Y-257292D01*
X659922Y-257376D01*
G01X617322Y-274459D02*
X817322D01*
G01X734955Y-301959D02*
Y-306959D01*
X737489D01*
G01X740562Y-301959D02*
X742082D01*
G01X741322D02*
Y-306959D01*
G01X740562D02*
X742082D01*
G01X746929Y-304292D02*
X747182Y-304042D01*
X747372Y-303626D01*
X747499Y-303042D01*
X747372Y-302542D01*
X747119Y-302209D01*
X746675Y-301959D01*
X744965D01*
Y-306959D01*
X747055D01*
X747499Y-306626D01*
X747752Y-306126D01*
X747879Y-305542D01*
X747752Y-304959D01*
X747372Y-304459D01*
X746929Y-304292D01*
X744965D01*
G01X751522Y-307126D02*
X751395Y-307042D01*
Y-306876D01*
X751522Y-306792D01*
X751649Y-306876D01*
Y-307042D01*
X751522Y-307126D01*
G01Y-304876D02*
X751395Y-304792D01*
Y-304626D01*
X751522Y-304542D01*
X751649Y-304626D01*
Y-304792D01*
X751522Y-304876D01*
G01X732322Y-299459D02*
Y-324459D01*
G01X779222Y-301959D02*
Y-306959D01*
G01X777765Y-301959D02*
X780679D01*
G01X784322Y-306959D02*
X783942Y-306876D01*
X783562Y-306542D01*
X783309Y-305959D01*
X783182Y-305292D01*
X783309Y-304626D01*
X783562Y-304042D01*
X783942Y-303709D01*
X784322Y-303626D01*
X784702Y-303709D01*
X785082Y-304042D01*
X785335Y-304626D01*
X785399Y-305292D01*
X785335Y-305959D01*
X785082Y-306542D01*
X784702Y-306876D01*
X784322Y-306959D01*
G01X789422D02*
X789042Y-306876D01*
X788662Y-306542D01*
X788409Y-305959D01*
X788282Y-305292D01*
X788409Y-304626D01*
X788662Y-304042D01*
X789042Y-303709D01*
X789422Y-303626D01*
X789802Y-303709D01*
X790182Y-304042D01*
X790435Y-304626D01*
X790499Y-305292D01*
X790435Y-305959D01*
X790182Y-306542D01*
X789802Y-306876D01*
X789422Y-306959D01*
G01X794522D02*
Y-301959D01*
G01X799622Y-307126D02*
X799495Y-307042D01*
Y-306876D01*
X799622Y-306792D01*
X799749Y-306876D01*
Y-307042D01*
X799622Y-307126D01*
G01Y-304876D02*
X799495Y-304792D01*
Y-304626D01*
X799622Y-304542D01*
X799749Y-304626D01*
Y-304792D01*
X799622Y-304876D01*
G01X775322Y-299459D02*
Y-324459D01*
G01Y-274459D02*
Y-299459D01*
G01X777955Y-281959D02*
Y-276959D01*
X779539D01*
X780045Y-277209D01*
X780362Y-277542D01*
X780489Y-278209D01*
X780362Y-278876D01*
X779982Y-279292D01*
X779539Y-279542D01*
X777955D01*
G01X779539D02*
X780489Y-281959D01*
G01X785589D02*
X783055D01*
Y-276959D01*
X785589D01*
G01X784575Y-279376D02*
X783055D01*
G01X787839Y-276959D02*
X789422Y-281959D01*
X791005Y-276959D01*
G01X794522Y-282126D02*
X794395Y-282042D01*
Y-281876D01*
X794522Y-281792D01*
X794649Y-281876D01*
Y-282042D01*
X794522Y-282126D01*
G01Y-279876D02*
X794395Y-279792D01*
Y-279626D01*
X794522Y-279542D01*
X794649Y-279626D01*
Y-279792D01*
X794522Y-279876D01*
G01X798082Y-326159D02*
X798162Y-326084D01*
X798222Y-325959D01*
X798262Y-325784D01*
X798222Y-325634D01*
X798142Y-325534D01*
X798002Y-325459D01*
X797462D01*
Y-326959D01*
X798122D01*
X798262Y-326859D01*
X798342Y-326709D01*
X798382Y-326534D01*
X798342Y-326359D01*
X798222Y-326209D01*
X798082Y-326159D01*
X797462D01*
G01X799482Y-326959D02*
Y-325959D01*
G01Y-326134D02*
X799402Y-326034D01*
X799282Y-325984D01*
X799142Y-325959D01*
X799002Y-326009D01*
X798882Y-326109D01*
X798802Y-326259D01*
X798762Y-326459D01*
X798802Y-326659D01*
X798882Y-326809D01*
X799002Y-326909D01*
X799142Y-326959D01*
X799282Y-326934D01*
X799402Y-326859D01*
X799482Y-326759D01*
G01X800022Y-326784D02*
X800122Y-326884D01*
X800262Y-326959D01*
X800382D01*
X800502Y-326909D01*
X800582Y-326834D01*
X800622Y-326734D01*
X800602Y-326584D01*
X800522Y-326509D01*
X800162Y-326359D01*
X800082Y-326184D01*
X800122Y-326059D01*
X800202Y-325984D01*
X800322Y-325959D01*
X800442Y-325984D01*
X800562Y-326059D01*
G01X801222Y-326284D02*
X801862D01*
X801802Y-326109D01*
X801702Y-326009D01*
X801562Y-325959D01*
X801422Y-325984D01*
X801302Y-326059D01*
X801222Y-326234D01*
X801182Y-326384D01*
Y-326534D01*
X801222Y-326684D01*
X801322Y-326834D01*
X801442Y-326934D01*
X801582Y-326959D01*
X801722Y-326909D01*
X801862Y-326759D01*
G01X802362Y-326959D02*
Y-325459D01*
G01Y-326209D02*
X802462Y-326059D01*
X802582Y-325984D01*
X802702Y-325959D01*
X802882Y-326009D01*
X803002Y-326109D01*
X803082Y-326284D01*
Y-326484D01*
X803042Y-326684D01*
X802962Y-326834D01*
X802822Y-326934D01*
X802702Y-326959D01*
X802582Y-326934D01*
X802462Y-326859D01*
X802362Y-326734D01*
G01X803922Y-326959D02*
X803802Y-326934D01*
X803682Y-326834D01*
X803602Y-326659D01*
X803562Y-326459D01*
X803602Y-326259D01*
X803682Y-326084D01*
X803802Y-325984D01*
X803922Y-325959D01*
X804042Y-325984D01*
X804162Y-326084D01*
X804242Y-326259D01*
X804262Y-326459D01*
X804242Y-326659D01*
X804162Y-326834D01*
X804042Y-326934D01*
X803922Y-326959D01*
G01X805482D02*
Y-325959D01*
G01Y-326134D02*
X805402Y-326034D01*
X805282Y-325984D01*
X805142Y-325959D01*
X805002Y-326009D01*
X804882Y-326109D01*
X804802Y-326259D01*
X804762Y-326459D01*
X804802Y-326659D01*
X804882Y-326809D01*
X805002Y-326909D01*
X805142Y-326959D01*
X805282Y-326934D01*
X805402Y-326859D01*
X805482Y-326759D01*
G01X806042Y-326959D02*
Y-325959D01*
G01Y-326159D02*
X806142Y-326059D01*
X806242Y-325984D01*
X806382Y-325959D01*
X806482Y-325984D01*
X806602Y-326059D01*
G01X807882Y-325459D02*
Y-326959D01*
G01Y-326734D02*
X807802Y-326859D01*
X807682Y-326934D01*
X807542Y-326959D01*
X807382Y-326909D01*
X807262Y-326784D01*
X807182Y-326634D01*
X807162Y-326459D01*
X807182Y-326284D01*
X807262Y-326134D01*
X807382Y-326009D01*
X807542Y-325959D01*
X807682Y-325984D01*
X807782Y-326034D01*
X807882Y-326134D01*
G01X809522Y-326959D02*
Y-325459D01*
X810022D01*
X810182Y-325534D01*
X810282Y-325634D01*
X810322Y-325834D01*
X810282Y-326034D01*
X810162Y-326159D01*
X810022Y-326234D01*
X809522D01*
G01X810022D02*
X810322Y-326959D01*
G01X810822Y-326284D02*
X811462D01*
X811402Y-326109D01*
X811302Y-326009D01*
X811162Y-325959D01*
X811022Y-325984D01*
X810902Y-326059D01*
X810822Y-326234D01*
X810782Y-326384D01*
Y-326534D01*
X810822Y-326684D01*
X810922Y-326834D01*
X811042Y-326934D01*
X811182Y-326959D01*
X811322Y-326909D01*
X811462Y-326759D01*
G01X811962Y-325959D02*
X812322Y-326959D01*
X812682Y-325959D01*
G01X813522Y-327009D02*
X813482Y-326984D01*
Y-326934D01*
X813522Y-326909D01*
X813562Y-326934D01*
Y-326984D01*
X813522Y-327009D01*
G01X814682Y-326959D02*
X814722Y-326634D01*
X814782Y-326359D01*
X814862Y-326109D01*
X814962Y-325834D01*
X815122Y-325459D01*
X814322D01*
G01X816082Y-326159D02*
X816162Y-326084D01*
X816222Y-325959D01*
X816262Y-325784D01*
X816222Y-325634D01*
X816142Y-325534D01*
X816002Y-325459D01*
X815462D01*
Y-326959D01*
X816122D01*
X816262Y-326859D01*
X816342Y-326709D01*
X816382Y-326534D01*
X816342Y-326359D01*
X816222Y-326209D01*
X816082Y-326159D01*
X815462D01*
G01X-320500Y-470483D02*
Y2626000D01*
X2967000D01*
Y-470483D01*
X-320500D01*
G01X-45318Y842784D02*
X-71544D01*
X-58431Y808208D01*
X-45318Y842784D01*
G01X-45014Y845087D02*
X-45206Y844777D01*
X-45436Y844570D01*
X-45704Y844467D01*
X-46011Y844570D01*
X-46241Y844777D01*
X-46471Y845087D01*
X-46548Y845500D01*
Y847567D01*
G01X-48229Y844829D02*
X-48498Y844570D01*
X-48804Y844467D01*
X-49111Y844570D01*
X-49379Y844880D01*
X-49571Y845345D01*
X-49648Y845810D01*
Y846379D01*
X-49571Y846844D01*
X-49379Y847257D01*
X-49149Y847464D01*
X-48881Y847567D01*
X-48574Y847464D01*
X-48344Y847257D01*
X-48191Y846947D01*
X-48114Y846534D01*
X-48191Y846172D01*
X-48383Y845810D01*
X-48613Y845604D01*
X-48881Y845552D01*
X-49188Y845655D01*
X-49418Y845914D01*
X-49648Y846379D01*
G01X-51138Y844932D02*
X-51368Y844674D01*
X-51636Y844519D01*
X-51981Y844467D01*
X-52326Y844570D01*
X-52594Y844777D01*
X-52786Y845139D01*
X-52824Y845552D01*
X-52748Y845965D01*
X-52556Y846224D01*
X-52288Y846430D01*
X-52019Y846482D01*
X-51751Y846430D01*
X-51406Y846224D01*
X-51521Y847567D01*
X-52556D01*
G01X-32883Y1143620D02*
X-33075Y1143310D01*
X-33305Y1143103D01*
X-33573Y1143000D01*
X-33880Y1143103D01*
X-34110Y1143310D01*
X-34340Y1143620D01*
X-34417Y1144033D01*
Y1146100D01*
G01X-36750Y1143000D02*
X-37018Y1143052D01*
X-37325Y1143207D01*
X-37517Y1143465D01*
X-37593Y1143827D01*
X-37517Y1144188D01*
X-37287Y1144498D01*
X-36942Y1144653D01*
X-36558D01*
X-36328Y1144757D01*
X-36137Y1145015D01*
X-36060Y1145377D01*
X-36175Y1145738D01*
X-36443Y1145997D01*
X-36750Y1146100D01*
X-37057Y1145997D01*
X-37325Y1145738D01*
X-37440Y1145377D01*
X-37363Y1145015D01*
X-37172Y1144757D01*
X-36942Y1144653D01*
X-36558D01*
X-36213Y1144498D01*
X-35983Y1144188D01*
X-35907Y1143827D01*
X-35983Y1143465D01*
X-36175Y1143207D01*
X-36482Y1143052D01*
X-36750Y1143000D01*
G01X-39007Y1143465D02*
X-39237Y1143207D01*
X-39505Y1143052D01*
X-39850Y1143000D01*
X-40195Y1143103D01*
X-40463Y1143310D01*
X-40655Y1143672D01*
X-40693Y1144085D01*
X-40617Y1144498D01*
X-40425Y1144757D01*
X-40157Y1144963D01*
X-39888Y1145015D01*
X-39620Y1144963D01*
X-39275Y1144757D01*
X-39390Y1146100D01*
X-40425D01*
G01X-40431Y1147216D02*
X-14205D01*
X-27318Y1181792D01*
X-40431Y1147216D01*
G01X7227Y162000D02*
X4987D01*
G01X6200Y163625D02*
Y160375D01*
G01X9096Y235964D02*
X11596D01*
X11096Y235644D01*
G01X9096D02*
Y236284D01*
G01Y238164D02*
X9138Y238351D01*
X9263Y238564D01*
X9471Y238697D01*
X9763Y238751D01*
X10054Y238697D01*
X10304Y238537D01*
X10429Y238297D01*
Y238031D01*
X10513Y237871D01*
X10721Y237737D01*
X11013Y237684D01*
X11304Y237764D01*
X11513Y237951D01*
X11596Y238164D01*
X11513Y238377D01*
X11304Y238564D01*
X11013Y238644D01*
X10721Y238591D01*
X10513Y238457D01*
X10429Y238297D01*
Y238031D01*
X10304Y237791D01*
X10054Y237631D01*
X9763Y237577D01*
X9471Y237631D01*
X9263Y237764D01*
X9138Y237977D01*
X9096Y238164D01*
G01X8996Y226364D02*
X11496D01*
X10996Y226044D01*
G01X8996D02*
Y226684D01*
G01X10038Y228057D02*
X10329Y228244D01*
X10496Y228404D01*
X10579Y228617D01*
X10496Y228804D01*
X10329Y228937D01*
X10079Y229044D01*
X9788Y229071D01*
X9538Y229044D01*
X9288Y228937D01*
X9079Y228777D01*
X8996Y228591D01*
X9079Y228377D01*
X9329Y228191D01*
X9704Y228084D01*
X10121Y228057D01*
X10663Y228111D01*
X10954Y228191D01*
X11246Y228324D01*
X11454Y228511D01*
X11496Y228697D01*
X11413Y228884D01*
X11204Y229017D01*
G01X8600Y252128D02*
Y258328D01*
X5400D01*
Y252128D01*
X8600D01*
G01X11000Y331587D02*
Y334013D01*
G01X19117Y871000D02*
Y874100D01*
X18197D01*
X17890Y873945D01*
X17660Y873583D01*
X17583Y873170D01*
X17660Y872757D01*
X17852Y872447D01*
X18197Y872292D01*
X19117D01*
G01X16093Y871000D02*
Y874100D01*
X15327D01*
X15020Y873945D01*
X14790Y873738D01*
X14598Y873428D01*
X14445Y873067D01*
X14407Y872550D01*
X14445Y872033D01*
X14598Y871672D01*
X14790Y871362D01*
X15020Y871155D01*
X15327Y871000D01*
X16093D01*
G01X12150D02*
Y874100D01*
X12610Y873480D01*
G01Y871000D02*
X11690D01*
G01X9778Y873583D02*
X9548Y873893D01*
X9280Y874048D01*
X8973Y874100D01*
X8590Y873997D01*
X8322Y873738D01*
X8245Y873428D01*
X8283Y873118D01*
X8437Y872860D01*
X9203Y872343D01*
X9548Y871982D01*
X9778Y871465D01*
X9855Y871000D01*
X8245D01*
G01X7550Y887482D02*
X5310D01*
G01X6523Y889107D02*
Y885857D01*
G01X8223Y887582D02*
Y875338D01*
X46223D01*
Y887582D01*
G01Y899826D02*
X8223D01*
Y887582D01*
G01X7860Y962190D02*
X10360D01*
X9860Y961870D01*
G01X7860D02*
Y962510D01*
G01Y964390D02*
X7902Y964577D01*
X8027Y964790D01*
X8235Y964923D01*
X8527Y964977D01*
X8818Y964923D01*
X9068Y964763D01*
X9193Y964523D01*
Y964257D01*
X9277Y964097D01*
X9485Y963963D01*
X9777Y963910D01*
X10068Y963990D01*
X10277Y964177D01*
X10360Y964390D01*
X10277Y964603D01*
X10068Y964790D01*
X9777Y964870D01*
X9485Y964817D01*
X9277Y964683D01*
X9193Y964523D01*
Y964257D01*
X9068Y964017D01*
X8818Y963857D01*
X8527Y963803D01*
X8235Y963857D01*
X8027Y963990D01*
X7902Y964203D01*
X7860Y964390D01*
G01X8996Y953136D02*
X11496D01*
X10996Y952816D01*
G01X8996D02*
Y953456D01*
G01X10038Y954829D02*
X10329Y955016D01*
X10496Y955176D01*
X10579Y955389D01*
X10496Y955576D01*
X10329Y955709D01*
X10079Y955816D01*
X9788Y955843D01*
X9538Y955816D01*
X9288Y955709D01*
X9079Y955549D01*
X8996Y955363D01*
X9079Y955149D01*
X9329Y954963D01*
X9704Y954856D01*
X10121Y954829D01*
X10663Y954883D01*
X10954Y954963D01*
X11246Y955096D01*
X11454Y955283D01*
X11496Y955469D01*
X11413Y955656D01*
X11204Y955789D01*
G01X8100Y978900D02*
Y985100D01*
X4900D01*
Y978900D01*
X8100D01*
G01X13500Y1013273D02*
Y1015513D01*
G01X15125Y1014300D02*
X11875D01*
G01X11000Y1062327D02*
Y1060087D01*
G01X9375Y1061300D02*
X12625D01*
G01X45950Y1307000D02*
G03I-25950J0D01*
G01X69950Y17500D02*
G03I-25950J0D01*
G01X51378Y121791D02*
Y31043D01*
X9252D01*
Y121791D01*
X51378D01*
G01X26496Y43248D02*
X21457D01*
Y71692D01*
G01Y81142D02*
X9252D01*
G01X21457Y71692D02*
X9252D01*
G01X21457Y81142D02*
Y109586D01*
X39173D01*
G01X15117Y123620D02*
X14925Y123310D01*
X14695Y123103D01*
X14427Y123000D01*
X14120Y123103D01*
X13890Y123310D01*
X13660Y123620D01*
X13583Y124033D01*
Y126100D01*
G01X12093Y123465D02*
X11863Y123207D01*
X11595Y123052D01*
X11250Y123000D01*
X10905Y123103D01*
X10637Y123310D01*
X10445Y123672D01*
X10407Y124085D01*
X10483Y124498D01*
X10675Y124757D01*
X10943Y124963D01*
X11212Y125015D01*
X11480Y124963D01*
X11825Y124757D01*
X11710Y126100D01*
X10675D01*
G01X17917Y146700D02*
Y149800D01*
X16997D01*
X16690Y149645D01*
X16460Y149283D01*
X16383Y148870D01*
X16460Y148457D01*
X16652Y148147D01*
X16997Y147992D01*
X17917D01*
G01X14893Y146700D02*
Y149800D01*
X14127D01*
X13820Y149645D01*
X13590Y149438D01*
X13398Y149128D01*
X13245Y148767D01*
X13207Y148250D01*
X13245Y147733D01*
X13398Y147372D01*
X13590Y147062D01*
X13820Y146855D01*
X14127Y146700D01*
X14893D01*
G01X11027D02*
X10950Y147372D01*
X10835Y147940D01*
X10682Y148457D01*
X10490Y149025D01*
X10183Y149800D01*
X11717D01*
G01X9844Y162928D02*
Y150684D01*
X47844D01*
Y162928D01*
G01X33344D02*
X24844Y158928D01*
Y166928D01*
X32844Y162928D01*
G01X47844Y175172D02*
X9844D01*
Y162928D01*
G01X24544D02*
X22144D01*
G01X15344Y184500D02*
Y177100D01*
X32744D01*
Y184500D01*
X15344D01*
G01X15295Y194306D02*
Y186906D01*
X32695D01*
Y194306D01*
X15295D01*
G01X15351Y204006D02*
Y196606D01*
X32751D01*
Y204006D01*
X15351D01*
G01X15851Y211906D02*
Y205906D01*
X27851D01*
Y211906D01*
X15851D01*
G01X12929Y218831D02*
Y221331D01*
X13249Y220831D01*
G01Y218831D02*
X12609D01*
G01X11316Y219206D02*
X11156Y218998D01*
X10969Y218873D01*
X10729Y218831D01*
X10489Y218914D01*
X10302Y219081D01*
X10169Y219373D01*
X10142Y219706D01*
X10196Y220039D01*
X10329Y220248D01*
X10516Y220414D01*
X10702Y220456D01*
X10889Y220414D01*
X11129Y220248D01*
X11049Y221331D01*
X10329D01*
G01X14568Y220664D02*
Y218664D01*
G01X22442Y220664D02*
Y216664D01*
G01X30316Y220664D02*
Y218664D01*
G01X13629Y222225D02*
X13190D01*
Y223464D01*
G01X13129Y243331D02*
Y245831D01*
X13449Y245331D01*
G01Y243331D02*
X12809D01*
G01X11382Y243623D02*
X11196Y243414D01*
X10982Y243331D01*
X10769Y243414D01*
X10582Y243664D01*
X10449Y244039D01*
X10396Y244414D01*
Y244873D01*
X10449Y245248D01*
X10582Y245581D01*
X10742Y245748D01*
X10929Y245831D01*
X11142Y245748D01*
X11302Y245581D01*
X11409Y245331D01*
X11462Y244998D01*
X11409Y244706D01*
X11276Y244414D01*
X11116Y244248D01*
X10929Y244206D01*
X10716Y244289D01*
X10556Y244498D01*
X10396Y244873D01*
G01X24016Y245864D02*
Y243864D01*
G01X16142Y247864D02*
Y243864D01*
G01X13190Y241064D02*
Y242303D01*
G01Y238164D02*
Y239164D01*
G01Y234964D02*
Y235864D01*
G01Y228664D02*
Y232664D01*
G01Y225364D02*
Y226364D01*
G01Y242303D02*
X13629D01*
G01X36993Y274600D02*
Y272378D01*
X36840Y271913D01*
X36533Y271603D01*
X36150Y271500D01*
X35767Y271603D01*
X35460Y271913D01*
X35307Y272378D01*
Y274600D01*
G01X33893Y272120D02*
X33663Y271758D01*
X33357Y271552D01*
X33012Y271500D01*
X32705Y271552D01*
X32398Y271810D01*
X32207Y272120D01*
X32168Y272430D01*
X32245Y272792D01*
X32513Y273050D01*
X32782Y273153D01*
X33127D01*
G01X32782D02*
X32552Y273308D01*
X32360Y273567D01*
X32283Y273877D01*
X32360Y274187D01*
X32552Y274445D01*
X32897Y274600D01*
X33242Y274548D01*
X33587Y274342D01*
G01X30793Y271965D02*
X30563Y271707D01*
X30295Y271552D01*
X29950Y271500D01*
X29605Y271603D01*
X29337Y271810D01*
X29145Y272172D01*
X29107Y272585D01*
X29183Y272998D01*
X29375Y273257D01*
X29643Y273463D01*
X29912Y273515D01*
X30180Y273463D01*
X30525Y273257D01*
X30410Y274600D01*
X29375D01*
G01X27502Y271862D02*
X27233Y271603D01*
X26927Y271500D01*
X26620Y271603D01*
X26352Y271913D01*
X26160Y272378D01*
X26083Y272843D01*
Y273412D01*
X26160Y273877D01*
X26352Y274290D01*
X26582Y274497D01*
X26850Y274600D01*
X27157Y274497D01*
X27387Y274290D01*
X27540Y273980D01*
X27617Y273567D01*
X27540Y273205D01*
X27348Y272843D01*
X27118Y272637D01*
X26850Y272585D01*
X26543Y272688D01*
X26313Y272947D01*
X26083Y273412D01*
G01X37991Y270128D02*
X24591D01*
G01X30291Y261328D02*
X24591D01*
G01Y270128D02*
Y261328D01*
G01X32291D02*
X31291Y262928D01*
X30291Y261328D01*
G01X23600Y264307D02*
X21378D01*
X20913Y264460D01*
X20603Y264767D01*
X20500Y265150D01*
X20603Y265533D01*
X20913Y265840D01*
X21378Y265993D01*
X23600D01*
G01X21120Y267407D02*
X20758Y267637D01*
X20552Y267943D01*
X20500Y268288D01*
X20552Y268595D01*
X20810Y268902D01*
X21120Y269093D01*
X21430Y269132D01*
X21792Y269055D01*
X22050Y268787D01*
X22153Y268518D01*
Y268173D01*
G01Y268518D02*
X22308Y268748D01*
X22567Y268940D01*
X22877Y269017D01*
X23187Y268940D01*
X23445Y268748D01*
X23600Y268403D01*
X23548Y268058D01*
X23342Y267713D01*
G01X20862Y270698D02*
X20603Y270967D01*
X20500Y271273D01*
X20603Y271580D01*
X20913Y271848D01*
X21378Y272040D01*
X21843Y272117D01*
X22412D01*
X22877Y272040D01*
X23290Y271848D01*
X23497Y271618D01*
X23600Y271350D01*
X23497Y271043D01*
X23290Y270813D01*
X22980Y270660D01*
X22567Y270583D01*
X22205Y270660D01*
X21843Y270852D01*
X21637Y271082D01*
X21585Y271350D01*
X21688Y271657D01*
X21947Y271887D01*
X22412Y272117D01*
G01X23083Y273722D02*
X23393Y273952D01*
X23548Y274220D01*
X23600Y274527D01*
X23497Y274910D01*
X23238Y275178D01*
X22928Y275255D01*
X22618Y275217D01*
X22360Y275063D01*
X21843Y274297D01*
X21482Y273952D01*
X20965Y273722D01*
X20500Y273645D01*
Y275255D01*
G01X19700Y272800D02*
Y262200D01*
X10300D01*
Y272800D01*
X19600D01*
G01X21400Y251900D02*
X27600D01*
Y255100D01*
X21400D01*
Y251900D01*
G01X9400Y258364D02*
Y252164D01*
X12600D01*
Y258364D01*
X9400D01*
G01X20600Y252164D02*
Y258364D01*
X17400D01*
Y252164D01*
X20600D01*
G01X16600D02*
Y258364D01*
X13400D01*
Y252164D01*
X16600D01*
G01X31600D02*
Y258364D01*
X28400D01*
Y252164D01*
X31600D01*
G01X27600Y259100D02*
X21400D01*
Y255900D01*
X27600D01*
Y259100D01*
G01X22500Y282273D02*
Y284513D01*
G01X24125Y283300D02*
X20875D01*
G01X8941Y290432D02*
Y330524D01*
X33429D01*
Y290432D01*
X8941D01*
G01X21685Y311228D02*
Y314228D01*
G01X25685Y311728D02*
X17685D01*
G01X24685Y306228D02*
X18685D01*
X21685Y311228D01*
X24685Y306228D01*
G01X21685Y303228D02*
Y306228D01*
G01X29500Y335827D02*
Y333587D01*
G01X27875Y334800D02*
X31125D01*
G01X21685Y336792D02*
X33929D01*
Y374792D01*
X21685D01*
G01X9441D02*
Y336792D01*
X21685D01*
G01Y360292D02*
X25685Y351792D01*
X17685D01*
X21685Y359792D01*
G01Y351492D02*
Y349092D01*
G01Y360292D02*
Y362892D01*
G01X16185Y360292D02*
X27185D01*
G01X29500Y380513D02*
Y378087D01*
G01X9441Y376292D02*
X33929D01*
G01X9441Y375592D02*
X33929D01*
G01X9441Y375192D02*
X33929D01*
G01X9441Y375992D02*
X33929D01*
G01X9441Y376792D02*
Y374742D01*
G01X21685Y374792D02*
X9441D01*
G01X21685Y376792D02*
X33929D01*
G01X9441D02*
X21685D01*
G01X51378Y485177D02*
Y394429D01*
X9252D01*
Y485177D01*
X51378D01*
G01X26496Y406634D02*
X21457D01*
Y435078D01*
G01Y444528D02*
X9252D01*
G01X21457Y435078D02*
X9252D01*
G01X21457Y444528D02*
Y472972D01*
X39173D01*
G01X18117Y487120D02*
X17925Y486810D01*
X17695Y486603D01*
X17427Y486500D01*
X17120Y486603D01*
X16890Y486810D01*
X16660Y487120D01*
X16583Y487533D01*
Y489600D01*
G01X14978Y487792D02*
X14710Y488153D01*
X14480Y488360D01*
X14173Y488463D01*
X13905Y488360D01*
X13713Y488153D01*
X13560Y487843D01*
X13522Y487482D01*
X13560Y487172D01*
X13713Y486862D01*
X13943Y486603D01*
X14212Y486500D01*
X14518Y486603D01*
X14787Y486913D01*
X14940Y487378D01*
X14978Y487895D01*
X14902Y488567D01*
X14787Y488928D01*
X14595Y489290D01*
X14327Y489548D01*
X14058Y489600D01*
X13790Y489497D01*
X13598Y489238D01*
G01X51378Y848563D02*
Y757815D01*
X9252D01*
Y848563D01*
X51378D01*
G01X26496Y770020D02*
X21457D01*
Y798464D01*
G01D02*
X9252D01*
G01X21457Y807914D02*
X9252D01*
G01X21457D02*
Y836358D01*
X39173D01*
G01X15117Y850620D02*
X14925Y850310D01*
X14695Y850103D01*
X14427Y850000D01*
X14120Y850103D01*
X13890Y850310D01*
X13660Y850620D01*
X13583Y851033D01*
Y853100D01*
G01X11327Y850000D02*
X11250Y850672D01*
X11135Y851240D01*
X10982Y851757D01*
X10790Y852325D01*
X10483Y853100D01*
X12017D01*
G01X31723Y887582D02*
X23223Y883582D01*
Y891582D01*
X31223Y887582D01*
G01X22923D02*
X20523D01*
G01X31723D02*
X34323D01*
G01X31723Y893082D02*
Y882082D01*
G01X13332Y920062D02*
Y912662D01*
X30732D01*
Y920062D01*
X13332D01*
G01Y909562D02*
Y902162D01*
X30732D01*
Y909562D01*
X13332D01*
G01X13962Y938899D02*
Y932899D01*
X25962D01*
Y938899D01*
X13962D01*
G01X37767Y940650D02*
Y943750D01*
X36847D01*
X36540Y943595D01*
X36310Y943233D01*
X36233Y942820D01*
X36310Y942407D01*
X36502Y942097D01*
X36847Y941942D01*
X37767D01*
G01X34743Y943750D02*
Y941528D01*
X34590Y941063D01*
X34283Y940753D01*
X33900Y940650D01*
X33517Y940753D01*
X33210Y941063D01*
X33057Y941528D01*
Y943750D01*
G01X30800Y940650D02*
X30532Y940702D01*
X30225Y940857D01*
X30033Y941115D01*
X29957Y941477D01*
X30033Y941838D01*
X30263Y942148D01*
X30608Y942303D01*
X30992D01*
X31222Y942407D01*
X31413Y942665D01*
X31490Y943027D01*
X31375Y943388D01*
X31107Y943647D01*
X30800Y943750D01*
X30493Y943647D01*
X30225Y943388D01*
X30110Y943027D01*
X30187Y942665D01*
X30378Y942407D01*
X30608Y942303D01*
X30992D01*
X31337Y942148D01*
X31567Y941838D01*
X31643Y941477D01*
X31567Y941115D01*
X31375Y940857D01*
X31068Y940702D01*
X30800Y940650D01*
G01X13332Y930562D02*
Y923162D01*
X30732D01*
Y930562D01*
X13332D01*
G01X12929Y945603D02*
Y948103D01*
X13249Y947603D01*
G01Y945603D02*
X12609D01*
G01X11316Y945978D02*
X11156Y945770D01*
X10969Y945645D01*
X10729Y945603D01*
X10489Y945686D01*
X10302Y945853D01*
X10169Y946145D01*
X10142Y946478D01*
X10196Y946811D01*
X10329Y947020D01*
X10516Y947186D01*
X10702Y947228D01*
X10889Y947186D01*
X11129Y947020D01*
X11049Y948103D01*
X10329D01*
G01X14568Y947436D02*
Y945436D01*
G01X22442Y947436D02*
Y943436D01*
G01X30316Y947436D02*
Y945436D01*
G01X13190Y961736D02*
Y962636D01*
G01Y955436D02*
Y959436D01*
G01Y952136D02*
Y953136D01*
G01X13629Y948997D02*
X13190D01*
Y950236D01*
G01X13129Y970103D02*
Y972603D01*
X13449Y972103D01*
G01Y970103D02*
X12809D01*
G01X11382Y970395D02*
X11196Y970186D01*
X10982Y970103D01*
X10769Y970186D01*
X10582Y970436D01*
X10449Y970811D01*
X10396Y971186D01*
Y971645D01*
X10449Y972020D01*
X10582Y972353D01*
X10742Y972520D01*
X10929Y972603D01*
X11142Y972520D01*
X11302Y972353D01*
X11409Y972103D01*
X11462Y971770D01*
X11409Y971478D01*
X11276Y971186D01*
X11116Y971020D01*
X10929Y970978D01*
X10716Y971061D01*
X10556Y971270D01*
X10396Y971645D01*
G01X24016Y972636D02*
Y970636D01*
G01X16142Y974636D02*
Y970636D01*
G01X13190Y967836D02*
Y969075D01*
G01Y964936D02*
Y965936D01*
G01Y969075D02*
X13629D01*
G01X21400Y978900D02*
X27600D01*
Y982100D01*
X21400D01*
Y978900D01*
G01X8900Y985100D02*
Y978900D01*
X12100D01*
Y985100D01*
X8900D01*
G01X20100Y978900D02*
Y985100D01*
X16900D01*
Y978900D01*
X20100D01*
G01X16100D02*
Y985100D01*
X12900D01*
Y978900D01*
X16100D01*
G01X32100D02*
Y985100D01*
X28900D01*
Y978900D01*
X32100D01*
G01X27600Y986100D02*
X21400D01*
Y982900D01*
X27600D01*
Y986100D01*
G01X38493Y1001100D02*
Y998878D01*
X38340Y998413D01*
X38033Y998103D01*
X37650Y998000D01*
X37267Y998103D01*
X36960Y998413D01*
X36807Y998878D01*
Y1001100D01*
G01X35393Y998620D02*
X35163Y998258D01*
X34857Y998052D01*
X34512Y998000D01*
X34205Y998052D01*
X33898Y998310D01*
X33707Y998620D01*
X33668Y998930D01*
X33745Y999292D01*
X34013Y999550D01*
X34282Y999653D01*
X34627D01*
G01X34282D02*
X34052Y999808D01*
X33860Y1000067D01*
X33783Y1000377D01*
X33860Y1000687D01*
X34052Y1000945D01*
X34397Y1001100D01*
X34742Y1001048D01*
X35087Y1000842D01*
G01X31450Y998000D02*
X31182Y998052D01*
X30875Y998207D01*
X30683Y998465D01*
X30607Y998827D01*
X30683Y999188D01*
X30913Y999498D01*
X31258Y999653D01*
X31642D01*
X31872Y999757D01*
X32063Y1000015D01*
X32140Y1000377D01*
X32025Y1000738D01*
X31757Y1000997D01*
X31450Y1001100D01*
X31143Y1000997D01*
X30875Y1000738D01*
X30760Y1000377D01*
X30837Y1000015D01*
X31028Y999757D01*
X31258Y999653D01*
X31642D01*
X31987Y999498D01*
X32217Y999188D01*
X32293Y998827D01*
X32217Y998465D01*
X32025Y998207D01*
X31718Y998052D01*
X31450Y998000D01*
G01X29193Y998620D02*
X28963Y998258D01*
X28657Y998052D01*
X28312Y998000D01*
X28005Y998052D01*
X27698Y998310D01*
X27507Y998620D01*
X27468Y998930D01*
X27545Y999292D01*
X27813Y999550D01*
X28082Y999653D01*
X28427D01*
G01X28082D02*
X27852Y999808D01*
X27660Y1000067D01*
X27583Y1000377D01*
X27660Y1000687D01*
X27852Y1000945D01*
X28197Y1001100D01*
X28542Y1001048D01*
X28887Y1000842D01*
G01X37991Y996900D02*
X24591D01*
G01X30291Y988100D02*
X24591D01*
G01Y996900D02*
Y988100D01*
G01X32291D02*
X31291Y989700D01*
X30291Y988100D01*
G01X24693Y1004600D02*
Y1002378D01*
X24540Y1001913D01*
X24233Y1001603D01*
X23850Y1001500D01*
X23467Y1001603D01*
X23160Y1001913D01*
X23007Y1002378D01*
Y1004600D01*
G01X21593Y1002120D02*
X21363Y1001758D01*
X21057Y1001552D01*
X20712Y1001500D01*
X20405Y1001552D01*
X20098Y1001810D01*
X19907Y1002120D01*
X19868Y1002430D01*
X19945Y1002792D01*
X20213Y1003050D01*
X20482Y1003153D01*
X20827D01*
G01X20482D02*
X20252Y1003308D01*
X20060Y1003567D01*
X19983Y1003877D01*
X20060Y1004187D01*
X20252Y1004445D01*
X20597Y1004600D01*
X20942Y1004548D01*
X21287Y1004342D01*
G01X18302Y1001862D02*
X18033Y1001603D01*
X17727Y1001500D01*
X17420Y1001603D01*
X17152Y1001913D01*
X16960Y1002378D01*
X16883Y1002843D01*
Y1003412D01*
X16960Y1003877D01*
X17152Y1004290D01*
X17382Y1004497D01*
X17650Y1004600D01*
X17957Y1004497D01*
X18187Y1004290D01*
X18340Y1003980D01*
X18417Y1003567D01*
X18340Y1003205D01*
X18148Y1002843D01*
X17918Y1002637D01*
X17650Y1002585D01*
X17343Y1002688D01*
X17113Y1002947D01*
X16883Y1003412D01*
G01X14627Y1001500D02*
X14550Y1002172D01*
X14435Y1002740D01*
X14282Y1003257D01*
X14090Y1003825D01*
X13783Y1004600D01*
X15317D01*
G01X19700Y1000300D02*
Y989700D01*
X10300D01*
Y1000300D01*
X19600D01*
G01X9441Y1017204D02*
Y1057296D01*
X33929D01*
Y1017204D01*
X9441D01*
G01X25185Y1033000D02*
X19185D01*
X22185Y1038000D01*
X25185Y1033000D01*
G01X22185Y1030000D02*
Y1033000D01*
G01X29000Y1058087D02*
Y1060513D01*
G01X22185Y1038000D02*
Y1041000D01*
G01X26185Y1038500D02*
X18185D01*
G01X21685Y1087064D02*
X25685Y1078564D01*
X17685D01*
X21685Y1086564D01*
G01Y1063564D02*
X33929D01*
Y1101564D01*
X21685D01*
G01X9441D02*
Y1063564D01*
X21685D01*
G01Y1078264D02*
Y1075864D01*
G01X14500Y1107013D02*
Y1104587D01*
G01X9441Y1102364D02*
X33929D01*
G01X9441Y1101964D02*
X33929D01*
G01X9441Y1102764D02*
X33929D01*
G01X9441Y1103564D02*
Y1101514D01*
G01X21685Y1101564D02*
X9441D01*
G01X21685Y1087064D02*
Y1089664D01*
G01X16185Y1087064D02*
X27185D01*
G01X9441Y1103064D02*
X33929D01*
G01X21685Y1103564D02*
X33929D01*
G01X9441D02*
X21685D01*
G01X51378Y1211949D02*
Y1121201D01*
X9252D01*
Y1211949D01*
X51378D01*
G01X26496Y1133406D02*
X21457D01*
Y1161850D01*
G01Y1171300D02*
X9252D01*
G01X21457Y1161850D02*
X9252D01*
G01X21457Y1171300D02*
Y1199744D01*
X39173D01*
G01X18117Y1214120D02*
X17925Y1213810D01*
X17695Y1213603D01*
X17427Y1213500D01*
X17120Y1213603D01*
X16890Y1213810D01*
X16660Y1214120D01*
X16583Y1214533D01*
Y1216600D01*
G01X14250Y1213500D02*
X13982Y1213552D01*
X13675Y1213707D01*
X13483Y1213965D01*
X13407Y1214327D01*
X13483Y1214688D01*
X13713Y1214998D01*
X14058Y1215153D01*
X14442D01*
X14672Y1215257D01*
X14863Y1215515D01*
X14940Y1215877D01*
X14825Y1216238D01*
X14557Y1216497D01*
X14250Y1216600D01*
X13943Y1216497D01*
X13675Y1216238D01*
X13560Y1215877D01*
X13637Y1215515D01*
X13828Y1215257D01*
X14058Y1215153D01*
X14442D01*
X14787Y1214998D01*
X15017Y1214688D01*
X15093Y1214327D01*
X15017Y1213965D01*
X14825Y1213707D01*
X14518Y1213552D01*
X14250Y1213500D01*
G01X14900Y1230700D02*
X25100D01*
Y1235300D01*
X14900D01*
Y1230700D01*
G01X39173Y109586D02*
Y43248D01*
X34133D01*
G01X49344Y175172D02*
Y150684D01*
G01X48644Y175172D02*
Y150684D01*
G01X48244Y175172D02*
Y150684D01*
G01X49044Y175172D02*
Y150684D01*
G01X47794D02*
X49894D01*
G01X49844Y162928D02*
Y150684D01*
G01X53557Y162928D02*
X51131D01*
G01X49844Y175172D02*
X47794D01*
G01X47844Y162928D02*
Y175172D01*
G01X33344Y162928D02*
X35944D01*
G01X33344Y168428D02*
Y157428D01*
G01X49844Y175172D02*
Y162928D01*
G01X43617Y222000D02*
Y225100D01*
X42697D01*
X42390Y224945D01*
X42160Y224583D01*
X42083Y224170D01*
X42160Y223757D01*
X42352Y223447D01*
X42697Y223292D01*
X43617D01*
G01X40593Y225100D02*
Y222878D01*
X40440Y222413D01*
X40133Y222103D01*
X39750Y222000D01*
X39367Y222103D01*
X39060Y222413D01*
X38907Y222878D01*
Y225100D01*
G01X37378Y223292D02*
X37110Y223653D01*
X36880Y223860D01*
X36573Y223963D01*
X36305Y223860D01*
X36113Y223653D01*
X35960Y223343D01*
X35922Y222982D01*
X35960Y222672D01*
X36113Y222362D01*
X36343Y222103D01*
X36612Y222000D01*
X36918Y222103D01*
X37187Y222413D01*
X37340Y222878D01*
X37378Y223395D01*
X37302Y224067D01*
X37187Y224428D01*
X36995Y224790D01*
X36727Y225048D01*
X36458Y225100D01*
X36190Y224997D01*
X35998Y224738D01*
G01X33309Y218731D02*
Y221231D01*
X34296Y219439D01*
X32962D01*
G01X33268Y223464D02*
Y222225D01*
X32829D01*
G01X43667Y243728D02*
X37667D01*
Y231728D01*
X43667D01*
Y243728D01*
G01X36516Y243631D02*
X36356Y243339D01*
X36142Y243173D01*
X35902Y243131D01*
X35689Y243173D01*
X35476Y243381D01*
X35342Y243631D01*
X35316Y243881D01*
X35369Y244173D01*
X35556Y244381D01*
X35742Y244464D01*
X35982D01*
G01X35742D02*
X35582Y244589D01*
X35449Y244798D01*
X35396Y245048D01*
X35449Y245298D01*
X35582Y245506D01*
X35822Y245631D01*
X36062Y245589D01*
X36302Y245423D01*
G01X33729Y245631D02*
X33942Y245548D01*
X34102Y245339D01*
X34209Y245089D01*
X34289Y244756D01*
X34316Y244381D01*
X34289Y244006D01*
X34209Y243673D01*
X34102Y243423D01*
X33942Y243214D01*
X33729Y243131D01*
X33516Y243214D01*
X33356Y243423D01*
X33249Y243673D01*
X33169Y244006D01*
X33142Y244381D01*
X33169Y244756D01*
X33249Y245089D01*
X33356Y245339D01*
X33516Y245548D01*
X33729Y245631D01*
G01X35596Y226977D02*
X35304Y227137D01*
X35138Y227351D01*
X35096Y227591D01*
X35138Y227804D01*
X35346Y228017D01*
X35596Y228151D01*
X35846Y228177D01*
X36138Y228124D01*
X36346Y227937D01*
X36429Y227751D01*
Y227511D01*
G01Y227751D02*
X36554Y227911D01*
X36763Y228044D01*
X37013Y228097D01*
X37263Y228044D01*
X37471Y227911D01*
X37596Y227671D01*
X37554Y227431D01*
X37388Y227191D01*
G01X31890Y247864D02*
Y243864D01*
G01X33268Y226364D02*
Y225364D01*
G01Y229564D02*
Y228664D01*
G01Y235864D02*
Y231864D01*
G01Y239164D02*
Y238164D01*
G01X32829Y242303D02*
X33268D01*
Y241064D01*
G01X57667Y230141D02*
Y227715D01*
G01X70411Y271024D02*
Y230932D01*
X45923D01*
Y271024D01*
X70411D01*
G01X37991Y261328D02*
X32291D01*
G01X37991D02*
Y270128D01*
G01X52993Y275100D02*
Y272878D01*
X52840Y272413D01*
X52533Y272103D01*
X52150Y272000D01*
X51767Y272103D01*
X51460Y272413D01*
X51307Y272878D01*
Y275100D01*
G01X49893Y272620D02*
X49663Y272258D01*
X49357Y272052D01*
X49012Y272000D01*
X48705Y272052D01*
X48398Y272310D01*
X48207Y272620D01*
X48168Y272930D01*
X48245Y273292D01*
X48513Y273550D01*
X48782Y273653D01*
X49127D01*
G01X48782D02*
X48552Y273808D01*
X48360Y274067D01*
X48283Y274377D01*
X48360Y274687D01*
X48552Y274945D01*
X48897Y275100D01*
X49242Y275048D01*
X49587Y274842D01*
G01X46678Y273292D02*
X46410Y273653D01*
X46180Y273860D01*
X45873Y273963D01*
X45605Y273860D01*
X45413Y273653D01*
X45260Y273343D01*
X45222Y272982D01*
X45260Y272672D01*
X45413Y272362D01*
X45643Y272103D01*
X45912Y272000D01*
X46218Y272103D01*
X46487Y272413D01*
X46640Y272878D01*
X46678Y273395D01*
X46602Y274067D01*
X46487Y274428D01*
X46295Y274790D01*
X46027Y275048D01*
X45758Y275100D01*
X45490Y274997D01*
X45298Y274738D01*
G01X42850Y272000D02*
Y275100D01*
X43310Y274480D01*
G01Y272000D02*
X42390D01*
G01X39829Y252164D02*
Y258364D01*
X36629D01*
Y252164D01*
X39829D01*
G01X35829D02*
Y258364D01*
X32629D01*
Y252164D01*
X35829D01*
G01X43909D02*
Y258364D01*
X40709D01*
Y252164D01*
X43909D01*
G01X53667Y249728D02*
X61667D01*
G01X54667Y255228D02*
X60667D01*
X57667Y250228D01*
X54667Y255228D01*
G01X41361Y276328D02*
X54761D01*
G01X49061Y285128D02*
X54761D01*
G01X41361D02*
X47061D01*
G01X54761Y276328D02*
Y285128D01*
G01X41361D02*
Y276328D01*
G01X47061Y285128D02*
X48061Y283528D01*
X49061Y285128D01*
G01X39523Y294292D02*
Y288092D01*
X42723D01*
Y294292D01*
X39523D01*
G01X43523D02*
Y288092D01*
X46723D01*
Y294292D01*
X43523D01*
G01X47400Y294300D02*
Y288100D01*
X50600D01*
Y294300D01*
X47400D01*
G01X35461Y294292D02*
Y288092D01*
X38661D01*
Y294292D01*
X35461D01*
G01X57100Y288128D02*
Y294328D01*
X53900D01*
Y288128D01*
X57100D01*
G01X57767Y275055D02*
Y272815D01*
G01X56142Y274028D02*
X59392D01*
G01X35685Y302728D02*
X41685D01*
Y314728D01*
X35685D01*
Y302728D01*
G01X42836Y302825D02*
X42996Y303117D01*
X43210Y303283D01*
X43450Y303325D01*
X43663Y303283D01*
X43876Y303075D01*
X44010Y302825D01*
X44036Y302575D01*
X43983Y302283D01*
X43796Y302075D01*
X43610Y301992D01*
X43370D01*
G01X43610D02*
X43770Y301867D01*
X43903Y301658D01*
X43956Y301408D01*
X43903Y301158D01*
X43770Y300950D01*
X43530Y300825D01*
X43290Y300867D01*
X43050Y301033D01*
G01X45623Y300825D02*
X45410Y300908D01*
X45250Y301117D01*
X45143Y301367D01*
X45063Y301700D01*
X45036Y302075D01*
X45063Y302450D01*
X45143Y302783D01*
X45250Y303033D01*
X45410Y303242D01*
X45623Y303325D01*
X45836Y303242D01*
X45996Y303033D01*
X46103Y302783D01*
X46183Y302450D01*
X46210Y302075D01*
X46183Y301700D01*
X46103Y301367D01*
X45996Y301117D01*
X45836Y300908D01*
X45623Y300825D01*
G01X47462Y298592D02*
Y302592D01*
G01X46084Y316892D02*
Y317792D01*
G01Y310592D02*
Y314592D01*
G01Y307292D02*
Y308292D01*
G01X46523Y304153D02*
X46084D01*
Y305392D01*
G01X35052Y337375D02*
X38152D01*
Y338295D01*
X37997Y338602D01*
X37635Y338832D01*
X37222Y338909D01*
X36809Y338832D01*
X36499Y338640D01*
X36344Y338295D01*
Y337375D01*
G01X35052Y340399D02*
X38152D01*
Y341165D01*
X37997Y341472D01*
X37790Y341702D01*
X37480Y341894D01*
X37119Y342047D01*
X36602Y342085D01*
X36085Y342047D01*
X35724Y341894D01*
X35414Y341702D01*
X35207Y341472D01*
X35052Y341165D01*
Y340399D01*
G01Y344342D02*
X38152D01*
X37532Y343882D01*
G01X35052D02*
Y344802D01*
G01Y347442D02*
X38152D01*
X37532Y346982D01*
G01X35052D02*
Y347902D01*
G01X46043Y327725D02*
Y325225D01*
X45056Y327017D01*
X46390D01*
G01X43756Y319479D02*
X44048Y319319D01*
X44214Y319105D01*
X44256Y318865D01*
X44214Y318652D01*
X44006Y318439D01*
X43756Y318305D01*
X43506Y318279D01*
X43214Y318332D01*
X43006Y318519D01*
X42923Y318705D01*
Y318945D01*
G01Y318705D02*
X42798Y318545D01*
X42589Y318412D01*
X42339Y318359D01*
X42089Y318412D01*
X41881Y318545D01*
X41756Y318785D01*
X41798Y319025D01*
X41964Y319265D01*
G01X49036Y325792D02*
Y327792D01*
G01X46084Y322992D02*
Y324231D01*
X46523D01*
G01X46084Y320092D02*
Y321092D01*
G01X34500Y319883D02*
X37600D01*
Y320803D01*
X37445Y321110D01*
X37083Y321340D01*
X36670Y321417D01*
X36257Y321340D01*
X35947Y321148D01*
X35792Y320803D01*
Y319883D01*
G01X34500Y322907D02*
X37600D01*
Y323673D01*
X37445Y323980D01*
X37238Y324210D01*
X36928Y324402D01*
X36567Y324555D01*
X36050Y324593D01*
X35533Y324555D01*
X35172Y324402D01*
X34862Y324210D01*
X34655Y323980D01*
X34500Y323673D01*
Y322907D01*
G01Y326850D02*
X37600D01*
X36980Y326390D01*
G01X34500D02*
Y327310D01*
G01X35792Y329222D02*
X36153Y329490D01*
X36360Y329720D01*
X36463Y330027D01*
X36360Y330295D01*
X36153Y330487D01*
X35843Y330640D01*
X35482Y330678D01*
X35172Y330640D01*
X34862Y330487D01*
X34603Y330257D01*
X34500Y329988D01*
X34603Y329682D01*
X34913Y329413D01*
X35378Y329260D01*
X35895Y329222D01*
X36567Y329298D01*
X36928Y329413D01*
X37290Y329605D01*
X37548Y329873D01*
X37600Y330142D01*
X37497Y330410D01*
X37238Y330602D01*
G01X33929Y374742D02*
Y376842D01*
G01X39173Y472972D02*
Y406634D01*
X34133D01*
G01X35900Y662900D02*
X42100D01*
Y666100D01*
X35900D01*
Y662900D01*
G01X35963Y658919D02*
X42163D01*
Y662119D01*
X35963D01*
Y658919D01*
G01Y654919D02*
X42163D01*
Y658119D01*
X35963D01*
Y654919D01*
G01X35900Y666900D02*
X42100D01*
Y670100D01*
X35900D01*
Y666900D01*
G01Y682900D02*
X42100D01*
Y686100D01*
X35900D01*
Y682900D01*
G01Y678900D02*
X42100D01*
Y682100D01*
X35900D01*
Y678900D01*
G01Y670900D02*
X42100D01*
Y674100D01*
X35900D01*
Y670900D01*
G01Y674900D02*
X42100D01*
Y678100D01*
X35900D01*
Y674900D01*
G01X39173Y836358D02*
Y770020D01*
X34133D01*
G01X51936Y887582D02*
X49510D01*
G01X47723Y899826D02*
Y875338D01*
G01X47023Y899826D02*
Y875338D01*
G01X46623Y899826D02*
Y875338D01*
G01X47423Y899826D02*
Y875338D01*
G01X46173D02*
X48273D01*
G01X46223Y887582D02*
Y899826D01*
G01X48223Y887582D02*
Y875338D01*
G01Y899826D02*
Y887582D01*
G01Y899826D02*
X46173D01*
G01X43867Y971800D02*
X37867D01*
Y959800D01*
X43867D01*
Y971800D01*
G01X33309Y945503D02*
Y948003D01*
X34296Y946211D01*
X32962D01*
G01X35596Y953749D02*
X35304Y953909D01*
X35138Y954123D01*
X35096Y954363D01*
X35138Y954576D01*
X35346Y954789D01*
X35596Y954923D01*
X35846Y954949D01*
X36138Y954896D01*
X36346Y954709D01*
X36429Y954523D01*
Y954283D01*
G01Y954523D02*
X36554Y954683D01*
X36763Y954816D01*
X37013Y954869D01*
X37263Y954816D01*
X37471Y954683D01*
X37596Y954443D01*
X37554Y954203D01*
X37388Y953963D01*
G01X33268Y950236D02*
Y948997D01*
X32829D01*
G01X33268Y953136D02*
Y952136D01*
G01Y956336D02*
Y955436D01*
G01Y962636D02*
Y958636D01*
G01X58867Y954313D02*
Y951887D01*
G01X71611Y995196D02*
Y955104D01*
X47123D01*
Y995196D01*
X71611D01*
G01X36516Y970403D02*
X36356Y970111D01*
X36142Y969945D01*
X35902Y969903D01*
X35689Y969945D01*
X35476Y970153D01*
X35342Y970403D01*
X35316Y970653D01*
X35369Y970945D01*
X35556Y971153D01*
X35742Y971236D01*
X35982D01*
G01X35742D02*
X35582Y971361D01*
X35449Y971570D01*
X35396Y971820D01*
X35449Y972070D01*
X35582Y972278D01*
X35822Y972403D01*
X36062Y972361D01*
X36302Y972195D01*
G01X33729Y972403D02*
X33942Y972320D01*
X34102Y972111D01*
X34209Y971861D01*
X34289Y971528D01*
X34316Y971153D01*
X34289Y970778D01*
X34209Y970445D01*
X34102Y970195D01*
X33942Y969986D01*
X33729Y969903D01*
X33516Y969986D01*
X33356Y970195D01*
X33249Y970445D01*
X33169Y970778D01*
X33142Y971153D01*
X33169Y971528D01*
X33249Y971861D01*
X33356Y972111D01*
X33516Y972320D01*
X33729Y972403D01*
G01X31890Y974636D02*
Y970636D01*
G01X33268Y965936D02*
Y964936D01*
G01X32829Y969075D02*
X33268D01*
Y967836D01*
G01X40100Y978900D02*
Y985100D01*
X36900D01*
Y978900D01*
X40100D01*
G01X36100D02*
Y985100D01*
X32900D01*
Y978900D01*
X36100D01*
G01X44100D02*
Y985100D01*
X40900D01*
Y978900D01*
X44100D01*
G01X54867Y973900D02*
X62867D01*
G01X37991Y988100D02*
X32291D01*
G01X37991D02*
Y996900D01*
G01X54493Y1002100D02*
Y999878D01*
X54340Y999413D01*
X54033Y999103D01*
X53650Y999000D01*
X53267Y999103D01*
X52960Y999413D01*
X52807Y999878D01*
Y1002100D01*
G01X51393Y999620D02*
X51163Y999258D01*
X50857Y999052D01*
X50512Y999000D01*
X50205Y999052D01*
X49898Y999310D01*
X49707Y999620D01*
X49668Y999930D01*
X49745Y1000292D01*
X50013Y1000550D01*
X50282Y1000653D01*
X50627D01*
G01X50282D02*
X50052Y1000808D01*
X49860Y1001067D01*
X49783Y1001377D01*
X49860Y1001687D01*
X50052Y1001945D01*
X50397Y1002100D01*
X50742Y1002048D01*
X51087Y1001842D01*
G01X47450Y999000D02*
X47182Y999052D01*
X46875Y999207D01*
X46683Y999465D01*
X46607Y999827D01*
X46683Y1000188D01*
X46913Y1000498D01*
X47258Y1000653D01*
X47642D01*
X47872Y1000757D01*
X48063Y1001015D01*
X48140Y1001377D01*
X48025Y1001738D01*
X47757Y1001997D01*
X47450Y1002100D01*
X47143Y1001997D01*
X46875Y1001738D01*
X46760Y1001377D01*
X46837Y1001015D01*
X47028Y1000757D01*
X47258Y1000653D01*
X47642D01*
X47987Y1000498D01*
X48217Y1000188D01*
X48293Y999827D01*
X48217Y999465D01*
X48025Y999207D01*
X47718Y999052D01*
X47450Y999000D01*
G01X45193Y999465D02*
X44963Y999207D01*
X44695Y999052D01*
X44350Y999000D01*
X44005Y999103D01*
X43737Y999310D01*
X43545Y999672D01*
X43507Y1000085D01*
X43583Y1000498D01*
X43775Y1000757D01*
X44043Y1000963D01*
X44312Y1001015D01*
X44580Y1000963D01*
X44925Y1000757D01*
X44810Y1002100D01*
X43775D01*
G01X41861Y1003100D02*
X55261D01*
G01X41861Y1011900D02*
Y1003100D01*
G01X47561Y1011900D02*
X48561Y1010300D01*
X49561Y1011900D01*
G01X58000Y999727D02*
Y997487D01*
G01X56375Y998700D02*
X59625D01*
G01X36055Y1028168D02*
X42055D01*
Y1040168D01*
X36055D01*
Y1028168D01*
G01X49561Y1011900D02*
X55261D01*
G01X41861D02*
X47561D01*
G01X46687Y1028000D02*
X46527Y1027708D01*
X46313Y1027542D01*
X46073Y1027500D01*
X45860Y1027542D01*
X45647Y1027750D01*
X45513Y1028000D01*
X45487Y1028250D01*
X45540Y1028542D01*
X45727Y1028750D01*
X45913Y1028833D01*
X46153D01*
G01X45913D02*
X45753Y1028958D01*
X45620Y1029167D01*
X45567Y1029417D01*
X45620Y1029667D01*
X45753Y1029875D01*
X45993Y1030000D01*
X46233Y1029958D01*
X46473Y1029792D01*
G01X43900Y1030000D02*
X44113Y1029917D01*
X44273Y1029708D01*
X44380Y1029458D01*
X44460Y1029125D01*
X44487Y1028750D01*
X44460Y1028375D01*
X44380Y1028042D01*
X44273Y1027792D01*
X44113Y1027583D01*
X43900Y1027500D01*
X43687Y1027583D01*
X43527Y1027792D01*
X43420Y1028042D01*
X43340Y1028375D01*
X43313Y1028750D01*
X43340Y1029125D01*
X43420Y1029458D01*
X43527Y1029708D01*
X43687Y1029917D01*
X43900Y1030000D01*
G01X47962Y1025364D02*
Y1029364D01*
G01X47023Y1030925D02*
X46584D01*
Y1032164D01*
G01X40523Y1021064D02*
Y1014864D01*
X43723D01*
Y1021064D01*
X40523D01*
G01X44523D02*
Y1014864D01*
X47723D01*
Y1021064D01*
X44523D01*
G01X48400Y1021100D02*
Y1014900D01*
X51600D01*
Y1021100D01*
X48400D01*
G01X36461Y1021064D02*
Y1014864D01*
X39661D01*
Y1021064D01*
X36461D01*
G01X45180Y1052500D02*
Y1055000D01*
X46167Y1053208D01*
X44833D01*
G01X44087Y1045000D02*
X43927Y1044708D01*
X43713Y1044542D01*
X43473Y1044500D01*
X43260Y1044542D01*
X43047Y1044750D01*
X42913Y1045000D01*
X42887Y1045250D01*
X42940Y1045542D01*
X43127Y1045750D01*
X43313Y1045833D01*
X43553D01*
G01X43313D02*
X43153Y1045958D01*
X43020Y1046167D01*
X42967Y1046417D01*
X43020Y1046667D01*
X43153Y1046875D01*
X43393Y1047000D01*
X43633Y1046958D01*
X43873Y1046792D01*
G01X49536Y1052564D02*
Y1054564D01*
G01X46584Y1049764D02*
Y1051003D01*
X47023D01*
G01X46584Y1046864D02*
Y1047864D01*
G01Y1043664D02*
Y1044564D01*
G01Y1037364D02*
Y1041364D01*
G01Y1034064D02*
Y1035064D01*
G01X35000Y1045883D02*
X38100D01*
Y1046803D01*
X37945Y1047110D01*
X37583Y1047340D01*
X37170Y1047417D01*
X36757Y1047340D01*
X36447Y1047148D01*
X36292Y1046803D01*
Y1045883D01*
G01X35000Y1048907D02*
X38100D01*
Y1049673D01*
X37945Y1049980D01*
X37738Y1050210D01*
X37428Y1050402D01*
X37067Y1050555D01*
X36550Y1050593D01*
X36033Y1050555D01*
X35672Y1050402D01*
X35362Y1050210D01*
X35155Y1049980D01*
X35000Y1049673D01*
Y1048907D01*
G01Y1052850D02*
X38100D01*
X37480Y1052390D01*
G01X35000D02*
Y1053310D01*
G01Y1055950D02*
X35052Y1056218D01*
X35207Y1056525D01*
X35465Y1056717D01*
X35827Y1056793D01*
X36188Y1056717D01*
X36498Y1056487D01*
X36653Y1056142D01*
Y1055758D01*
X36757Y1055528D01*
X37015Y1055337D01*
X37377Y1055260D01*
X37738Y1055375D01*
X37997Y1055643D01*
X38100Y1055950D01*
X37997Y1056257D01*
X37738Y1056525D01*
X37377Y1056640D01*
X37015Y1056563D01*
X36757Y1056372D01*
X36653Y1056142D01*
Y1055758D01*
X36498Y1055413D01*
X36188Y1055183D01*
X35827Y1055107D01*
X35465Y1055183D01*
X35207Y1055375D01*
X35052Y1055682D01*
X35000Y1055950D01*
G01X35052Y1064147D02*
X38152D01*
Y1065067D01*
X37997Y1065374D01*
X37635Y1065604D01*
X37222Y1065681D01*
X36809Y1065604D01*
X36499Y1065412D01*
X36344Y1065067D01*
Y1064147D01*
G01X35052Y1067171D02*
X38152D01*
Y1067937D01*
X37997Y1068244D01*
X37790Y1068474D01*
X37480Y1068666D01*
X37119Y1068819D01*
X36602Y1068857D01*
X36085Y1068819D01*
X35724Y1068666D01*
X35414Y1068474D01*
X35207Y1068244D01*
X35052Y1067937D01*
Y1067171D01*
G01Y1071114D02*
X38152D01*
X37532Y1070654D01*
G01X35052D02*
Y1071574D01*
G01X35672Y1073371D02*
X35310Y1073601D01*
X35104Y1073907D01*
X35052Y1074252D01*
X35104Y1074559D01*
X35362Y1074866D01*
X35672Y1075057D01*
X35982Y1075096D01*
X36344Y1075019D01*
X36602Y1074751D01*
X36705Y1074482D01*
Y1074137D01*
G01Y1074482D02*
X36860Y1074712D01*
X37119Y1074904D01*
X37429Y1074981D01*
X37739Y1074904D01*
X37997Y1074712D01*
X38152Y1074367D01*
X38100Y1074022D01*
X37894Y1073677D01*
G01X33929Y1101514D02*
Y1103614D01*
G01X39173Y1199744D02*
Y1133406D01*
X34133D01*
G01X74252Y44685D02*
Y7283D01*
X80158Y1378D01*
X99489D01*
X105394Y7283D01*
Y43307D01*
G02X106772Y44685I1378J0D01*
G02X108150Y43307I0J-1378D01*
G01Y32635D01*
G01X129292Y47833D02*
X74252D01*
G01X72000Y231383D02*
X75100D01*
Y232303D01*
X74945Y232610D01*
X74583Y232840D01*
X74170Y232917D01*
X73757Y232840D01*
X73447Y232648D01*
X73292Y232303D01*
Y231383D01*
G01X72000Y234407D02*
X75100D01*
Y235173D01*
X74945Y235480D01*
X74738Y235710D01*
X74428Y235902D01*
X74067Y236055D01*
X73550Y236093D01*
X73033Y236055D01*
X72672Y235902D01*
X72362Y235710D01*
X72155Y235480D01*
X72000Y235173D01*
Y234407D01*
G01Y238350D02*
X75100D01*
X74480Y237890D01*
G01X72000D02*
Y238810D01*
G01X72465Y240607D02*
X72207Y240837D01*
X72052Y241105D01*
X72000Y241450D01*
X72103Y241795D01*
X72310Y242063D01*
X72672Y242255D01*
X73085Y242293D01*
X73498Y242217D01*
X73757Y242025D01*
X73963Y241757D01*
X74015Y241488D01*
X73963Y241220D01*
X73757Y240875D01*
X75100Y240990D01*
Y242025D01*
G01X57667Y250228D02*
Y247228D01*
G01Y258228D02*
Y255228D01*
G01X80100Y275807D02*
X77878D01*
X77413Y275960D01*
X77103Y276267D01*
X77000Y276650D01*
X77103Y277033D01*
X77413Y277340D01*
X77878Y277493D01*
X80100D01*
G01X77620Y278907D02*
X77258Y279137D01*
X77052Y279443D01*
X77000Y279788D01*
X77052Y280095D01*
X77310Y280402D01*
X77620Y280593D01*
X77930Y280632D01*
X78292Y280555D01*
X78550Y280287D01*
X78653Y280018D01*
Y279673D01*
G01Y280018D02*
X78808Y280248D01*
X79067Y280440D01*
X79377Y280517D01*
X79687Y280440D01*
X79945Y280248D01*
X80100Y279903D01*
X80048Y279558D01*
X79842Y279213D01*
G01X77362Y282198D02*
X77103Y282467D01*
X77000Y282773D01*
X77103Y283080D01*
X77413Y283348D01*
X77878Y283540D01*
X78343Y283617D01*
X78912D01*
X79377Y283540D01*
X79790Y283348D01*
X79997Y283118D01*
X80100Y282850D01*
X79997Y282543D01*
X79790Y282313D01*
X79480Y282160D01*
X79067Y282083D01*
X78705Y282160D01*
X78343Y282352D01*
X78137Y282582D01*
X78085Y282850D01*
X78188Y283157D01*
X78447Y283387D01*
X78912Y283617D01*
G01X77620Y285107D02*
X77258Y285337D01*
X77052Y285643D01*
X77000Y285988D01*
X77052Y286295D01*
X77310Y286602D01*
X77620Y286793D01*
X77930Y286832D01*
X78292Y286755D01*
X78550Y286487D01*
X78653Y286218D01*
Y285873D01*
G01Y286218D02*
X78808Y286448D01*
X79067Y286640D01*
X79377Y286717D01*
X79687Y286640D01*
X79945Y286448D01*
X80100Y286103D01*
X80048Y285758D01*
X79842Y285413D01*
G01X61861Y274928D02*
Y285528D01*
X71261D01*
Y274928D01*
X61961D01*
G01X57900Y294328D02*
Y288128D01*
X61100D01*
Y294328D01*
X57900D01*
G01X61900D02*
Y288128D01*
X65100D01*
Y294328D01*
X61900D01*
G01X66461D02*
Y288128D01*
X69661D01*
Y294328D01*
X66461D01*
G01X74161Y288128D02*
Y294328D01*
X70961D01*
Y288128D01*
X74161D01*
G01X75461Y294328D02*
Y288128D01*
X78661D01*
Y294328D01*
X75461D01*
G01X79617Y304000D02*
Y307100D01*
X78697D01*
X78390Y306945D01*
X78160Y306583D01*
X78083Y306170D01*
X78160Y305757D01*
X78352Y305447D01*
X78697Y305292D01*
X79617D01*
G01X76593Y307100D02*
Y304878D01*
X76440Y304413D01*
X76133Y304103D01*
X75750Y304000D01*
X75367Y304103D01*
X75060Y304413D01*
X74907Y304878D01*
Y307100D01*
G01X72727Y304000D02*
X72650Y304672D01*
X72535Y305240D01*
X72382Y305757D01*
X72190Y306325D01*
X71883Y307100D01*
X73417D01*
G01X66223Y303125D02*
Y300625D01*
X65903Y301125D01*
G01Y303125D02*
X66543D01*
G01X67970Y302833D02*
X68156Y303042D01*
X68370Y303125D01*
X68583Y303042D01*
X68770Y302792D01*
X68903Y302417D01*
X68956Y302042D01*
Y301583D01*
X68903Y301208D01*
X68770Y300875D01*
X68610Y300708D01*
X68423Y300625D01*
X68210Y300708D01*
X68050Y300875D01*
X67943Y301125D01*
X67890Y301458D01*
X67943Y301750D01*
X68076Y302042D01*
X68236Y302208D01*
X68423Y302250D01*
X68636Y302167D01*
X68796Y301958D01*
X68956Y301583D01*
G01X70256Y310492D02*
X67756D01*
X68256Y310812D01*
G01X70256D02*
Y310172D01*
G01Y308292D02*
X70214Y308105D01*
X70089Y307892D01*
X69881Y307759D01*
X69589Y307705D01*
X69298Y307759D01*
X69048Y307919D01*
X68923Y308159D01*
Y308425D01*
X68839Y308585D01*
X68631Y308719D01*
X68339Y308772D01*
X68048Y308692D01*
X67839Y308505D01*
X67756Y308292D01*
X67839Y308079D01*
X68048Y307892D01*
X68339Y307812D01*
X68631Y307865D01*
X68839Y307999D01*
X68923Y308159D01*
Y308425D01*
X69048Y308665D01*
X69298Y308825D01*
X69589Y308879D01*
X69881Y308825D01*
X70089Y308692D01*
X70214Y308479D01*
X70256Y308292D01*
G01X70356Y320092D02*
X67856D01*
X68356Y320412D01*
G01X70356D02*
Y319772D01*
G01X69314Y318399D02*
X69023Y318212D01*
X68856Y318052D01*
X68773Y317839D01*
X68856Y317652D01*
X69023Y317519D01*
X69273Y317412D01*
X69564Y317385D01*
X69814Y317412D01*
X70064Y317519D01*
X70273Y317679D01*
X70356Y317865D01*
X70273Y318079D01*
X70023Y318265D01*
X69648Y318372D01*
X69231Y318399D01*
X68689Y318345D01*
X68398Y318265D01*
X68106Y318132D01*
X67898Y317945D01*
X67856Y317759D01*
X67939Y317572D01*
X68148Y317439D01*
G01X55336Y300592D02*
Y302592D01*
G01X63210Y298592D02*
Y302592D01*
G01X66162Y305392D02*
Y304153D01*
G01Y308292D02*
Y307292D01*
G01Y311492D02*
Y310592D01*
G01Y317792D02*
Y313792D01*
G01Y304153D02*
X65723D01*
G01X72000Y336300D02*
Y342300D01*
X60000D01*
Y336300D01*
X72000D01*
G01X66423Y327625D02*
Y325125D01*
X66103Y325625D01*
G01Y327625D02*
X66743D01*
G01X68036Y327250D02*
X68196Y327458D01*
X68383Y327583D01*
X68623Y327625D01*
X68863Y327542D01*
X69050Y327375D01*
X69183Y327083D01*
X69210Y326750D01*
X69156Y326417D01*
X69023Y326208D01*
X68836Y326042D01*
X68650Y326000D01*
X68463Y326042D01*
X68223Y326208D01*
X68303Y325125D01*
X69023D01*
G01X64784Y325792D02*
Y327792D01*
G01X56910Y325792D02*
Y329792D01*
G01X66162Y321092D02*
Y320092D01*
G01X65723Y324231D02*
X66162D01*
Y322992D01*
G01X72500Y354528D02*
Y361928D01*
X55100D01*
Y354528D01*
X72500D01*
G01Y344528D02*
Y351928D01*
X55100D01*
Y344528D01*
X72500D01*
G01Y364528D02*
Y371928D01*
X55100D01*
Y364528D01*
X72500D01*
G01X66400Y499900D02*
X72600D01*
Y503100D01*
X66400D01*
Y499900D01*
G01Y495400D02*
X72600D01*
Y498600D01*
X66400D01*
Y495400D01*
G01Y517900D02*
X72600D01*
Y521100D01*
X66400D01*
Y517900D01*
G01Y522400D02*
X72600D01*
Y525600D01*
X66400D01*
Y522400D01*
G01Y513400D02*
X72600D01*
Y516600D01*
X66400D01*
Y513400D01*
G01Y508900D02*
X72600D01*
Y512100D01*
X66400D01*
Y508900D01*
G01Y504400D02*
X72600D01*
Y507600D01*
X66400D01*
Y504400D01*
G01Y526900D02*
X72600D01*
Y530100D01*
X66400D01*
Y526900D01*
G01X72700Y955283D02*
X75800D01*
Y956203D01*
X75645Y956510D01*
X75283Y956740D01*
X74870Y956817D01*
X74457Y956740D01*
X74147Y956548D01*
X73992Y956203D01*
Y955283D01*
G01X72700Y958307D02*
X75800D01*
Y959073D01*
X75645Y959380D01*
X75438Y959610D01*
X75128Y959802D01*
X74767Y959955D01*
X74250Y959993D01*
X73733Y959955D01*
X73372Y959802D01*
X73062Y959610D01*
X72855Y959380D01*
X72700Y959073D01*
Y958307D01*
G01Y962250D02*
X75800D01*
X75180Y961790D01*
G01X72700D02*
Y962710D01*
G01Y965273D02*
X73372Y965350D01*
X73940Y965465D01*
X74457Y965618D01*
X75025Y965810D01*
X75800Y966117D01*
Y964583D01*
G01X58867Y974400D02*
Y971400D01*
G01X55867Y979400D02*
X61867D01*
X58867Y974400D01*
X55867Y979400D01*
G01X58867Y982400D02*
Y979400D01*
G01X55261Y1003100D02*
Y1011900D01*
G01X80100Y1001307D02*
X77878D01*
X77413Y1001460D01*
X77103Y1001767D01*
X77000Y1002150D01*
X77103Y1002533D01*
X77413Y1002840D01*
X77878Y1002993D01*
X80100D01*
G01X77620Y1004407D02*
X77258Y1004637D01*
X77052Y1004943D01*
X77000Y1005288D01*
X77052Y1005595D01*
X77310Y1005902D01*
X77620Y1006093D01*
X77930Y1006132D01*
X78292Y1006055D01*
X78550Y1005787D01*
X78653Y1005518D01*
Y1005173D01*
G01Y1005518D02*
X78808Y1005748D01*
X79067Y1005940D01*
X79377Y1006017D01*
X79687Y1005940D01*
X79945Y1005748D01*
X80100Y1005403D01*
X80048Y1005058D01*
X79842Y1004713D01*
G01X77362Y1007698D02*
X77103Y1007967D01*
X77000Y1008273D01*
X77103Y1008580D01*
X77413Y1008848D01*
X77878Y1009040D01*
X78343Y1009117D01*
X78912D01*
X79377Y1009040D01*
X79790Y1008848D01*
X79997Y1008618D01*
X80100Y1008350D01*
X79997Y1008043D01*
X79790Y1007813D01*
X79480Y1007660D01*
X79067Y1007583D01*
X78705Y1007660D01*
X78343Y1007852D01*
X78137Y1008082D01*
X78085Y1008350D01*
X78188Y1008657D01*
X78447Y1008887D01*
X78912Y1009117D01*
G01X77000Y1011450D02*
X77052Y1011718D01*
X77207Y1012025D01*
X77465Y1012217D01*
X77827Y1012293D01*
X78188Y1012217D01*
X78498Y1011987D01*
X78653Y1011642D01*
Y1011258D01*
X78757Y1011028D01*
X79015Y1010837D01*
X79377Y1010760D01*
X79738Y1010875D01*
X79997Y1011143D01*
X80100Y1011450D01*
X79997Y1011757D01*
X79738Y1012025D01*
X79377Y1012140D01*
X79015Y1012063D01*
X78757Y1011872D01*
X78653Y1011642D01*
Y1011258D01*
X78498Y1010913D01*
X78188Y1010683D01*
X77827Y1010607D01*
X77465Y1010683D01*
X77207Y1010875D01*
X77052Y1011182D01*
X77000Y1011450D01*
G01X62361Y1001700D02*
Y1012300D01*
X71761D01*
Y1001700D01*
X62461D01*
G01X80617Y1030000D02*
Y1033100D01*
X79697D01*
X79390Y1032945D01*
X79160Y1032583D01*
X79083Y1032170D01*
X79160Y1031757D01*
X79352Y1031447D01*
X79697Y1031292D01*
X80617D01*
G01X77593Y1033100D02*
Y1030878D01*
X77440Y1030413D01*
X77133Y1030103D01*
X76750Y1030000D01*
X76367Y1030103D01*
X76060Y1030413D01*
X75907Y1030878D01*
Y1033100D01*
G01X74302Y1030362D02*
X74033Y1030103D01*
X73727Y1030000D01*
X73420Y1030103D01*
X73152Y1030413D01*
X72960Y1030878D01*
X72883Y1031343D01*
Y1031912D01*
X72960Y1032377D01*
X73152Y1032790D01*
X73382Y1032997D01*
X73650Y1033100D01*
X73957Y1032997D01*
X74187Y1032790D01*
X74340Y1032480D01*
X74417Y1032067D01*
X74340Y1031705D01*
X74148Y1031343D01*
X73918Y1031137D01*
X73650Y1031085D01*
X73343Y1031188D01*
X73113Y1031447D01*
X72883Y1031912D01*
G01X69600Y1028000D02*
Y1030500D01*
X69920Y1030000D01*
G01Y1028000D02*
X69280D01*
G01X67853Y1028292D02*
X67667Y1028083D01*
X67453Y1028000D01*
X67240Y1028083D01*
X67053Y1028333D01*
X66920Y1028708D01*
X66867Y1029083D01*
Y1029542D01*
X66920Y1029917D01*
X67053Y1030250D01*
X67213Y1030417D01*
X67400Y1030500D01*
X67613Y1030417D01*
X67773Y1030250D01*
X67880Y1030000D01*
X67933Y1029667D01*
X67880Y1029375D01*
X67747Y1029083D01*
X67587Y1028917D01*
X67400Y1028875D01*
X67187Y1028958D01*
X67027Y1029167D01*
X66867Y1029542D01*
G01X69000Y1034400D02*
X71500D01*
X71000Y1034080D01*
G01X69000D02*
Y1034720D01*
G01Y1036600D02*
X69042Y1036787D01*
X69167Y1037000D01*
X69375Y1037133D01*
X69667Y1037187D01*
X69958Y1037133D01*
X70208Y1036973D01*
X70333Y1036733D01*
Y1036467D01*
X70417Y1036307D01*
X70625Y1036173D01*
X70917Y1036120D01*
X71208Y1036200D01*
X71417Y1036387D01*
X71500Y1036600D01*
X71417Y1036813D01*
X71208Y1037000D01*
X70917Y1037080D01*
X70625Y1037027D01*
X70417Y1036893D01*
X70333Y1036733D01*
Y1036467D01*
X70208Y1036227D01*
X69958Y1036067D01*
X69667Y1036013D01*
X69375Y1036067D01*
X69167Y1036200D01*
X69042Y1036413D01*
X69000Y1036600D01*
G01X55836Y1027364D02*
Y1029364D01*
G01X63710Y1025364D02*
Y1029364D01*
G01X66662Y1032164D02*
Y1030925D01*
G01D02*
X66223D01*
G01X58900Y1021100D02*
Y1014900D01*
X62100D01*
Y1021100D01*
X58900D01*
G01X74161Y1014900D02*
Y1021100D01*
X70961D01*
Y1014900D01*
X74161D01*
G01X74961Y1021100D02*
Y1014900D01*
X78161D01*
Y1021100D01*
X74961D01*
G01X62900D02*
Y1014900D01*
X66100D01*
Y1021100D01*
X62900D01*
G01X66961D02*
Y1014900D01*
X70161D01*
Y1021100D01*
X66961D01*
G01X58100Y1014900D02*
Y1021100D01*
X54900D01*
Y1014900D01*
X58100D01*
G01X69000Y1044400D02*
X71500D01*
X71000Y1044080D01*
G01X69000D02*
Y1044720D01*
G01X70042Y1046093D02*
X70333Y1046280D01*
X70500Y1046440D01*
X70583Y1046653D01*
X70500Y1046840D01*
X70333Y1046973D01*
X70083Y1047080D01*
X69792Y1047107D01*
X69542Y1047080D01*
X69292Y1046973D01*
X69083Y1046813D01*
X69000Y1046627D01*
X69083Y1046413D01*
X69333Y1046227D01*
X69708Y1046120D01*
X70125Y1046093D01*
X70667Y1046147D01*
X70958Y1046227D01*
X71250Y1046360D01*
X71458Y1046547D01*
X71500Y1046733D01*
X71417Y1046920D01*
X71208Y1047053D01*
G01X69600Y1052000D02*
Y1054500D01*
X69920Y1054000D01*
G01Y1052000D02*
X69280D01*
G01X67987Y1052375D02*
X67827Y1052167D01*
X67640Y1052042D01*
X67400Y1052000D01*
X67160Y1052083D01*
X66973Y1052250D01*
X66840Y1052542D01*
X66813Y1052875D01*
X66867Y1053208D01*
X67000Y1053417D01*
X67187Y1053583D01*
X67373Y1053625D01*
X67560Y1053583D01*
X67800Y1053417D01*
X67720Y1054500D01*
X67000D01*
G01X65284Y1052564D02*
Y1054564D01*
G01X57410Y1052564D02*
Y1056564D01*
G01X66662Y1035064D02*
Y1034064D01*
G01Y1038264D02*
Y1037364D01*
G01Y1044564D02*
Y1040564D01*
G01Y1047864D02*
Y1046864D01*
G01X66223Y1051003D02*
X66662D01*
Y1049764D01*
G01X74149Y1059686D02*
Y1065686D01*
X62149D01*
Y1059686D01*
X74149D01*
G01X74774Y1078051D02*
Y1085451D01*
X57374D01*
Y1078051D01*
X74774D01*
G01Y1067551D02*
Y1074951D01*
X57374D01*
Y1067551D01*
X74774D01*
G01Y1088551D02*
Y1095951D01*
X57374D01*
Y1088551D01*
X74774D01*
G01X108799Y6634D02*
X114055Y1378D01*
X123386D01*
X129292Y7283D01*
Y44685D01*
G01X113500Y290383D02*
X116600D01*
Y291303D01*
X116445Y291610D01*
X116083Y291840D01*
X115670Y291917D01*
X115257Y291840D01*
X114947Y291648D01*
X114792Y291303D01*
Y290383D01*
G01X113500Y293407D02*
X116600D01*
Y294173D01*
X116445Y294480D01*
X116238Y294710D01*
X115928Y294902D01*
X115567Y295055D01*
X115050Y295093D01*
X114533Y295055D01*
X114172Y294902D01*
X113862Y294710D01*
X113655Y294480D01*
X113500Y294173D01*
Y293407D01*
G01X114792Y296622D02*
X115153Y296890D01*
X115360Y297120D01*
X115463Y297427D01*
X115360Y297695D01*
X115153Y297887D01*
X114843Y298040D01*
X114482Y298078D01*
X114172Y298040D01*
X113862Y297887D01*
X113603Y297657D01*
X113500Y297388D01*
X113603Y297082D01*
X113913Y296813D01*
X114378Y296660D01*
X114895Y296622D01*
X115567Y296698D01*
X115928Y296813D01*
X116290Y297005D01*
X116548Y297273D01*
X116600Y297542D01*
X116497Y297810D01*
X116238Y298002D01*
G01X118238Y290432D02*
Y330524D01*
X142726D01*
Y290432D01*
X118238D01*
G01X126600Y991307D02*
X124378D01*
X123913Y991460D01*
X123603Y991767D01*
X123500Y992150D01*
X123603Y992533D01*
X123913Y992840D01*
X124378Y992993D01*
X126600D01*
G01X124120Y994407D02*
X123758Y994637D01*
X123552Y994943D01*
X123500Y995288D01*
X123552Y995595D01*
X123810Y995902D01*
X124120Y996093D01*
X124430Y996132D01*
X124792Y996055D01*
X125050Y995787D01*
X125153Y995518D01*
Y995173D01*
G01Y995518D02*
X125308Y995748D01*
X125567Y995940D01*
X125877Y996017D01*
X126187Y995940D01*
X126445Y995748D01*
X126600Y995403D01*
X126548Y995058D01*
X126342Y994713D01*
G01X123862Y997698D02*
X123603Y997967D01*
X123500Y998273D01*
X123603Y998580D01*
X123913Y998848D01*
X124378Y999040D01*
X124843Y999117D01*
X125412D01*
X125877Y999040D01*
X126290Y998848D01*
X126497Y998618D01*
X126600Y998350D01*
X126497Y998043D01*
X126290Y997813D01*
X125980Y997660D01*
X125567Y997583D01*
X125205Y997660D01*
X124843Y997852D01*
X124637Y998082D01*
X124585Y998350D01*
X124688Y998657D01*
X124947Y998887D01*
X125412Y999117D01*
G01X123965Y1000607D02*
X123707Y1000837D01*
X123552Y1001105D01*
X123500Y1001450D01*
X123603Y1001795D01*
X123810Y1002063D01*
X124172Y1002255D01*
X124585Y1002293D01*
X124998Y1002217D01*
X125257Y1002025D01*
X125463Y1001757D01*
X125515Y1001488D01*
X125463Y1001220D01*
X125257Y1000875D01*
X126600Y1000990D01*
Y1002025D01*
G01X114000Y1017383D02*
X117100D01*
Y1018303D01*
X116945Y1018610D01*
X116583Y1018840D01*
X116170Y1018917D01*
X115757Y1018840D01*
X115447Y1018648D01*
X115292Y1018303D01*
Y1017383D01*
G01X114000Y1020407D02*
X117100D01*
Y1021173D01*
X116945Y1021480D01*
X116738Y1021710D01*
X116428Y1021902D01*
X116067Y1022055D01*
X115550Y1022093D01*
X115033Y1022055D01*
X114672Y1021902D01*
X114362Y1021710D01*
X114155Y1021480D01*
X114000Y1021173D01*
Y1020407D01*
G01X114620Y1023507D02*
X114258Y1023737D01*
X114052Y1024043D01*
X114000Y1024388D01*
X114052Y1024695D01*
X114310Y1025002D01*
X114620Y1025193D01*
X114930Y1025232D01*
X115292Y1025155D01*
X115550Y1024887D01*
X115653Y1024618D01*
Y1024273D01*
G01Y1024618D02*
X115808Y1024848D01*
X116067Y1025040D01*
X116377Y1025117D01*
X116687Y1025040D01*
X116945Y1024848D01*
X117100Y1024503D01*
X117048Y1024158D01*
X116842Y1023813D01*
G01X122500Y1013273D02*
Y1015513D01*
G01X124125Y1014300D02*
X120875D01*
G01X118238Y1017204D02*
Y1057296D01*
X142726D01*
Y1017204D01*
X118238D01*
G01X123000Y1081300D02*
Y1073900D01*
X140400D01*
Y1081300D01*
X123000D01*
G01Y1091800D02*
Y1084400D01*
X140400D01*
Y1091800D01*
X123000D01*
G01Y1102300D02*
Y1094900D01*
X140400D01*
Y1102300D01*
X123000D01*
G01X131620Y51550D02*
X130853D01*
Y50620D01*
X131083Y50310D01*
X131352Y50103D01*
X131735Y50000D01*
X132118Y50103D01*
X132387Y50310D01*
X132617Y50620D01*
X132770Y50982D01*
X132847Y51395D01*
Y51757D01*
X132770Y52067D01*
X132617Y52428D01*
X132387Y52738D01*
X132157Y52945D01*
X131850Y53100D01*
X131582D01*
X131275Y52997D01*
X131045Y52790D01*
G01X129478Y50000D02*
Y53100D01*
X128022D01*
G01X128558Y51602D02*
X129478D01*
G01X125650Y50000D02*
Y53100D01*
X126110Y52480D01*
G01Y50000D02*
X125190D01*
G01X144887Y169628D02*
X147313D01*
G01X136620Y218831D02*
Y221331D01*
X136940Y220831D01*
G01Y218831D02*
X136300D01*
G01X135007Y219206D02*
X134847Y218998D01*
X134660Y218873D01*
X134420Y218831D01*
X134180Y218914D01*
X133993Y219081D01*
X133860Y219373D01*
X133833Y219706D01*
X133887Y220039D01*
X134020Y220248D01*
X134207Y220414D01*
X134393Y220456D01*
X134580Y220414D01*
X134820Y220248D01*
X134740Y221331D01*
X134020D01*
G01X138259Y220664D02*
Y218664D01*
G01X146133Y220664D02*
Y216664D01*
G01X137320Y222225D02*
X136881D01*
Y223464D01*
G01X136820Y243331D02*
Y245831D01*
X137140Y245331D01*
G01Y243331D02*
X136500D01*
G01X135073Y243623D02*
X134887Y243414D01*
X134673Y243331D01*
X134460Y243414D01*
X134273Y243664D01*
X134140Y244039D01*
X134087Y244414D01*
Y244873D01*
X134140Y245248D01*
X134273Y245581D01*
X134433Y245748D01*
X134620Y245831D01*
X134833Y245748D01*
X134993Y245581D01*
X135100Y245331D01*
X135153Y244998D01*
X135100Y244706D01*
X134967Y244414D01*
X134807Y244248D01*
X134620Y244206D01*
X134407Y244289D01*
X134247Y244498D01*
X134087Y244873D01*
G01X132787Y235964D02*
X135287D01*
X134787Y235644D01*
G01X132787D02*
Y236284D01*
G01Y238164D02*
X132829Y238351D01*
X132954Y238564D01*
X133162Y238697D01*
X133454Y238751D01*
X133745Y238697D01*
X133995Y238537D01*
X134120Y238297D01*
Y238031D01*
X134204Y237871D01*
X134412Y237737D01*
X134704Y237684D01*
X134995Y237764D01*
X135204Y237951D01*
X135287Y238164D01*
X135204Y238377D01*
X134995Y238564D01*
X134704Y238644D01*
X134412Y238591D01*
X134204Y238457D01*
X134120Y238297D01*
Y238031D01*
X133995Y237791D01*
X133745Y237631D01*
X133454Y237577D01*
X133162Y237631D01*
X132954Y237764D01*
X132829Y237977D01*
X132787Y238164D01*
G01X132687Y226364D02*
X135187D01*
X134687Y226044D01*
G01X132687D02*
Y226684D01*
G01X133729Y228057D02*
X134020Y228244D01*
X134187Y228404D01*
X134270Y228617D01*
X134187Y228804D01*
X134020Y228937D01*
X133770Y229044D01*
X133479Y229071D01*
X133229Y229044D01*
X132979Y228937D01*
X132770Y228777D01*
X132687Y228591D01*
X132770Y228377D01*
X133020Y228191D01*
X133395Y228084D01*
X133812Y228057D01*
X134354Y228111D01*
X134645Y228191D01*
X134937Y228324D01*
X135145Y228511D01*
X135187Y228697D01*
X135104Y228884D01*
X134895Y229017D01*
G01X139833Y247864D02*
Y243864D01*
G01X136881Y241064D02*
Y242303D01*
G01Y238164D02*
Y239164D01*
G01Y234964D02*
Y235864D01*
G01Y228664D02*
Y232664D01*
G01Y225364D02*
Y226364D01*
G01Y242303D02*
X137320D01*
G01X130705Y261307D02*
X128483D01*
X128018Y261460D01*
X127708Y261767D01*
X127605Y262150D01*
X127708Y262533D01*
X128018Y262840D01*
X128483Y262993D01*
X130705D01*
G01X128225Y264407D02*
X127863Y264637D01*
X127657Y264943D01*
X127605Y265288D01*
X127657Y265595D01*
X127915Y265902D01*
X128225Y266093D01*
X128535Y266132D01*
X128897Y266055D01*
X129155Y265787D01*
X129258Y265518D01*
Y265173D01*
G01Y265518D02*
X129413Y265748D01*
X129672Y265940D01*
X129982Y266017D01*
X130292Y265940D01*
X130550Y265748D01*
X130705Y265403D01*
X130653Y265058D01*
X130447Y264713D01*
G01X127967Y267698D02*
X127708Y267967D01*
X127605Y268273D01*
X127708Y268580D01*
X128018Y268848D01*
X128483Y269040D01*
X128948Y269117D01*
X129517D01*
X129982Y269040D01*
X130395Y268848D01*
X130602Y268618D01*
X130705Y268350D01*
X130602Y268043D01*
X130395Y267813D01*
X130085Y267660D01*
X129672Y267583D01*
X129310Y267660D01*
X128948Y267852D01*
X128742Y268082D01*
X128690Y268350D01*
X128793Y268657D01*
X129052Y268887D01*
X129517Y269117D01*
G01X127605Y271450D02*
X130705D01*
X130085Y270990D01*
G01X127605D02*
Y271910D01*
G01X141182Y271528D02*
Y260928D01*
X131782D01*
Y271528D01*
X141082D01*
G01X145100Y252164D02*
Y258364D01*
X141900D01*
Y252164D01*
X145100D01*
G01X129900Y258364D02*
Y252164D01*
X133100D01*
Y258364D01*
X129900D01*
G01X129082Y252128D02*
Y258328D01*
X125882D01*
Y252128D01*
X129082D01*
G01X141100Y252164D02*
Y258364D01*
X137900D01*
Y252164D01*
X141100D01*
G01X137100D02*
Y258364D01*
X133900D01*
Y252164D01*
X137100D01*
G01X145900Y258364D02*
Y252164D01*
X149100D01*
Y258364D01*
X145900D01*
G01X149493Y285100D02*
Y282878D01*
X149340Y282413D01*
X149033Y282103D01*
X148650Y282000D01*
X148267Y282103D01*
X147960Y282413D01*
X147807Y282878D01*
Y285100D01*
G01X146393Y282620D02*
X146163Y282258D01*
X145857Y282052D01*
X145512Y282000D01*
X145205Y282052D01*
X144898Y282310D01*
X144707Y282620D01*
X144668Y282930D01*
X144745Y283292D01*
X145013Y283550D01*
X145282Y283653D01*
X145627D01*
G01X145282D02*
X145052Y283808D01*
X144860Y284067D01*
X144783Y284377D01*
X144860Y284687D01*
X145052Y284945D01*
X145397Y285100D01*
X145742Y285048D01*
X146087Y284842D01*
G01X142450Y282000D02*
X142182Y282052D01*
X141875Y282207D01*
X141683Y282465D01*
X141607Y282827D01*
X141683Y283188D01*
X141913Y283498D01*
X142258Y283653D01*
X142642D01*
X142872Y283757D01*
X143063Y284015D01*
X143140Y284377D01*
X143025Y284738D01*
X142757Y284997D01*
X142450Y285100D01*
X142143Y284997D01*
X141875Y284738D01*
X141760Y284377D01*
X141837Y284015D01*
X142028Y283757D01*
X142258Y283653D01*
X142642D01*
X142987Y283498D01*
X143217Y283188D01*
X143293Y282827D01*
X143217Y282465D01*
X143025Y282207D01*
X142718Y282052D01*
X142450Y282000D01*
G01X139350D02*
Y285100D01*
X139810Y284480D01*
G01Y282000D02*
X138890D01*
G01X146900Y294292D02*
Y288092D01*
X150100D01*
Y294292D01*
X146900D01*
G01X132000Y282273D02*
Y284513D01*
G01X133625Y283300D02*
X130375D01*
G01X144982Y302728D02*
X150982D01*
Y314728D01*
X144982D01*
Y302728D01*
G01X130982Y311228D02*
Y314228D01*
G01X134982Y311728D02*
X126982D01*
G01X133982Y306228D02*
X127982D01*
X130982Y311228D01*
X133982Y306228D01*
G01X130982Y303228D02*
Y306228D01*
G01X131500Y342000D02*
Y336000D01*
X143500D01*
Y342000D01*
X131500D01*
G01X130982Y331315D02*
Y333741D01*
G01X129700Y361728D02*
Y354328D01*
X147100D01*
Y361728D01*
X129700D01*
G01Y351728D02*
Y344328D01*
X147100D01*
Y351728D01*
X129700D01*
G01Y371728D02*
Y364328D01*
X147100D01*
Y371728D01*
X129700D01*
G01X148587Y887000D02*
X151013D01*
G01X132687Y956285D02*
X135187D01*
X134687Y955965D01*
G01X132687D02*
Y956605D01*
G01X133729Y957978D02*
X134020Y958165D01*
X134187Y958325D01*
X134270Y958538D01*
X134187Y958725D01*
X134020Y958858D01*
X133770Y958965D01*
X133479Y958992D01*
X133229Y958965D01*
X132979Y958858D01*
X132770Y958698D01*
X132687Y958512D01*
X132770Y958298D01*
X133020Y958112D01*
X133395Y958005D01*
X133812Y957978D01*
X134354Y958032D01*
X134645Y958112D01*
X134937Y958245D01*
X135145Y958432D01*
X135187Y958618D01*
X135104Y958805D01*
X134895Y958938D01*
G01X136620Y948752D02*
Y951252D01*
X136940Y950752D01*
G01Y948752D02*
X136300D01*
G01X135007Y949127D02*
X134847Y948919D01*
X134660Y948794D01*
X134420Y948752D01*
X134180Y948835D01*
X133993Y949002D01*
X133860Y949294D01*
X133833Y949627D01*
X133887Y949960D01*
X134020Y950169D01*
X134207Y950335D01*
X134393Y950377D01*
X134580Y950335D01*
X134820Y950169D01*
X134740Y951252D01*
X134020D01*
G01X138259Y950585D02*
Y948585D01*
G01X146133Y950585D02*
Y946585D01*
G01X136881Y958585D02*
Y962585D01*
G01Y955285D02*
Y956285D01*
G01X137320Y952146D02*
X136881D01*
Y953385D01*
G01X136820Y973252D02*
Y975752D01*
X137140Y975252D01*
G01Y973252D02*
X136500D01*
G01X135073Y973544D02*
X134887Y973335D01*
X134673Y973252D01*
X134460Y973335D01*
X134273Y973585D01*
X134140Y973960D01*
X134087Y974335D01*
Y974794D01*
X134140Y975169D01*
X134273Y975502D01*
X134433Y975669D01*
X134620Y975752D01*
X134833Y975669D01*
X134993Y975502D01*
X135100Y975252D01*
X135153Y974919D01*
X135100Y974627D01*
X134967Y974335D01*
X134807Y974169D01*
X134620Y974127D01*
X134407Y974210D01*
X134247Y974419D01*
X134087Y974794D01*
G01X132787Y965885D02*
X135287D01*
X134787Y965565D01*
G01X132787D02*
Y966205D01*
G01Y968085D02*
X132829Y968272D01*
X132954Y968485D01*
X133162Y968618D01*
X133454Y968672D01*
X133745Y968618D01*
X133995Y968458D01*
X134120Y968218D01*
Y967952D01*
X134204Y967792D01*
X134412Y967658D01*
X134704Y967605D01*
X134995Y967685D01*
X135204Y967872D01*
X135287Y968085D01*
X135204Y968298D01*
X134995Y968485D01*
X134704Y968565D01*
X134412Y968512D01*
X134204Y968378D01*
X134120Y968218D01*
Y967952D01*
X133995Y967712D01*
X133745Y967552D01*
X133454Y967498D01*
X133162Y967552D01*
X132954Y967685D01*
X132829Y967898D01*
X132787Y968085D01*
G01X139833Y977785D02*
Y973785D01*
G01X136881Y970985D02*
Y972224D01*
G01Y968085D02*
Y969085D01*
G01Y964885D02*
Y965785D01*
G01Y972224D02*
X137320D01*
G01X144100Y982085D02*
Y988285D01*
X140900D01*
Y982085D01*
X144100D01*
G01X128900Y988285D02*
Y982085D01*
X132100D01*
Y988285D01*
X128900D01*
G01X128100Y982085D02*
Y988285D01*
X124900D01*
Y982085D01*
X128100D01*
G01X140100D02*
Y988285D01*
X136900D01*
Y982085D01*
X140100D01*
G01X136100D02*
Y988285D01*
X132900D01*
Y982085D01*
X136100D01*
G01X144900Y988285D02*
Y982085D01*
X148100D01*
Y988285D01*
X144900D01*
G01X147793Y1012400D02*
Y1010178D01*
X147640Y1009713D01*
X147333Y1009403D01*
X146950Y1009300D01*
X146567Y1009403D01*
X146260Y1009713D01*
X146107Y1010178D01*
Y1012400D01*
G01X144693Y1009920D02*
X144463Y1009558D01*
X144157Y1009352D01*
X143812Y1009300D01*
X143505Y1009352D01*
X143198Y1009610D01*
X143007Y1009920D01*
X142968Y1010230D01*
X143045Y1010592D01*
X143313Y1010850D01*
X143582Y1010953D01*
X143927D01*
G01X143582D02*
X143352Y1011108D01*
X143160Y1011367D01*
X143083Y1011677D01*
X143160Y1011987D01*
X143352Y1012245D01*
X143697Y1012400D01*
X144042Y1012348D01*
X144387Y1012142D01*
G01X140827Y1009300D02*
X140750Y1009972D01*
X140635Y1010540D01*
X140482Y1011057D01*
X140290Y1011625D01*
X139983Y1012400D01*
X141517D01*
G01X137727Y1009300D02*
X137650Y1009972D01*
X137535Y1010540D01*
X137382Y1011057D01*
X137190Y1011625D01*
X136883Y1012400D01*
X138417D01*
G01X141182Y1001449D02*
Y990849D01*
X131782D01*
Y1001449D01*
X141082D01*
G01X144982Y1029500D02*
X150982D01*
Y1041500D01*
X144982D01*
Y1029500D01*
G01X145900Y1021100D02*
Y1014900D01*
X149100D01*
Y1021100D01*
X145900D01*
G01X133982Y1033000D02*
X127982D01*
X130982Y1038000D01*
X133982Y1033000D01*
G01X130982Y1030000D02*
Y1033000D01*
G01Y1058087D02*
Y1060513D01*
G01Y1038000D02*
Y1041000D01*
G01X134982Y1038500D02*
X126982D01*
G01X128500Y1072000D02*
Y1066000D01*
X140500D01*
Y1072000D01*
X128500D01*
G01X204450Y17500D02*
G03I-25950J0D01*
G01X152165Y31043D02*
Y121791D01*
X194291D01*
Y31043D01*
X152165D01*
G01X182086Y71692D02*
Y43248D01*
X164370D01*
G01D02*
Y109586D01*
X169410D01*
G01X165100Y169628D02*
X173600Y173628D01*
Y165628D01*
X165600Y169628D01*
G01X149100Y157384D02*
Y181872D01*
G01X149800Y157384D02*
Y181872D01*
G01X150200Y157384D02*
Y181872D01*
G01X149400Y157384D02*
Y181872D01*
G01X148600Y157384D02*
X150650D01*
G01X188600Y169628D02*
Y181872D01*
X150600D01*
Y169628D01*
G01D02*
Y157384D01*
G01X148600Y169628D02*
Y181872D01*
G01X150600Y157384D02*
X188600D01*
Y169628D01*
G01X165100D02*
X162500D01*
G01X165100Y164128D02*
Y175128D01*
G01X148600Y157384D02*
Y169628D01*
G01X150650Y181872D02*
X148550D01*
G01X184700Y183800D02*
Y191200D01*
X167300D01*
Y183800D01*
X184700D01*
G01Y193800D02*
Y201200D01*
X167300D01*
Y193800D01*
X184700D01*
G01X181900Y212900D02*
Y218900D01*
X169900D01*
Y212900D01*
X181900D01*
G01X167117Y222000D02*
Y225100D01*
X166197D01*
X165890Y224945D01*
X165660Y224583D01*
X165583Y224170D01*
X165660Y223757D01*
X165852Y223447D01*
X166197Y223292D01*
X167117D01*
G01X164093Y225100D02*
Y222878D01*
X163940Y222413D01*
X163633Y222103D01*
X163250Y222000D01*
X162867Y222103D01*
X162560Y222413D01*
X162407Y222878D01*
Y225100D01*
G01X160993Y222620D02*
X160763Y222258D01*
X160457Y222052D01*
X160112Y222000D01*
X159805Y222052D01*
X159498Y222310D01*
X159307Y222620D01*
X159268Y222930D01*
X159345Y223292D01*
X159613Y223550D01*
X159882Y223653D01*
X160227D01*
G01X159882D02*
X159652Y223808D01*
X159460Y224067D01*
X159383Y224377D01*
X159460Y224687D01*
X159652Y224945D01*
X159997Y225100D01*
X160342Y225048D01*
X160687Y224842D01*
G01X157000Y218731D02*
Y221231D01*
X157987Y219439D01*
X156653D01*
G01X154007Y220664D02*
Y218664D01*
G01X156959Y223464D02*
Y222225D01*
X156520D01*
G01X184600Y203700D02*
Y211100D01*
X167200D01*
Y203700D01*
X184600D01*
G01X167358Y243728D02*
X161358D01*
Y231728D01*
X167358D01*
Y243728D01*
G01X160207Y243631D02*
X160047Y243339D01*
X159833Y243173D01*
X159593Y243131D01*
X159380Y243173D01*
X159167Y243381D01*
X159033Y243631D01*
X159007Y243881D01*
X159060Y244173D01*
X159247Y244381D01*
X159433Y244464D01*
X159673D01*
G01X159433D02*
X159273Y244589D01*
X159140Y244798D01*
X159087Y245048D01*
X159140Y245298D01*
X159273Y245506D01*
X159513Y245631D01*
X159753Y245589D01*
X159993Y245423D01*
G01X157420Y245631D02*
X157633Y245548D01*
X157793Y245339D01*
X157900Y245089D01*
X157980Y244756D01*
X158007Y244381D01*
X157980Y244006D01*
X157900Y243673D01*
X157793Y243423D01*
X157633Y243214D01*
X157420Y243131D01*
X157207Y243214D01*
X157047Y243423D01*
X156940Y243673D01*
X156860Y244006D01*
X156833Y244381D01*
X156860Y244756D01*
X156940Y245089D01*
X157047Y245339D01*
X157207Y245548D01*
X157420Y245631D01*
G01X159287Y226977D02*
X158995Y227137D01*
X158829Y227351D01*
X158787Y227591D01*
X158829Y227804D01*
X159037Y228017D01*
X159287Y228151D01*
X159537Y228177D01*
X159829Y228124D01*
X160037Y227937D01*
X160120Y227751D01*
Y227511D01*
G01Y227751D02*
X160245Y227911D01*
X160454Y228044D01*
X160704Y228097D01*
X160954Y228044D01*
X161162Y227911D01*
X161287Y227671D01*
X161245Y227431D01*
X161079Y227191D01*
G01X147707Y245864D02*
Y243864D01*
G01X155581Y247864D02*
Y243864D01*
G01X156959Y226364D02*
Y225364D01*
G01Y229564D02*
Y228664D01*
G01Y235864D02*
Y231864D01*
G01Y239164D02*
Y238164D01*
G01X156520Y242303D02*
X156959D01*
Y241064D01*
G01X161548Y274100D02*
Y271878D01*
X161395Y271413D01*
X161088Y271103D01*
X160705Y271000D01*
X160322Y271103D01*
X160015Y271413D01*
X159862Y271878D01*
Y274100D01*
G01X157682Y271000D02*
X157605Y271672D01*
X157490Y272240D01*
X157337Y272757D01*
X157145Y273325D01*
X156838Y274100D01*
X158372D01*
G01X154045Y271000D02*
Y274100D01*
X155463Y271878D01*
X153547D01*
G01X161682Y270128D02*
X148282D01*
G01X153982Y261328D02*
X148282D01*
G01X161682D02*
X155982D01*
G01X148282Y270128D02*
Y261328D01*
G01X161682D02*
Y270128D01*
G01X155982Y261328D02*
X154982Y262928D01*
X153982Y261328D01*
G01X164020Y252164D02*
Y258364D01*
X160820D01*
Y252164D01*
X164020D01*
G01X160020D02*
Y258364D01*
X156820D01*
Y252164D01*
X160020D01*
G01X155600D02*
Y258364D01*
X152400D01*
Y252164D01*
X155600D01*
G01X168020D02*
Y258364D01*
X164820D01*
Y252164D01*
X168020D01*
G01X150658Y276328D02*
X164058D01*
G01X158358Y285128D02*
X164058D01*
G01X150658D02*
X156358D01*
G01X164058Y276328D02*
Y285128D01*
G01X150658D02*
Y276328D01*
G01X156358Y285128D02*
X157358Y283528D01*
X158358Y285128D01*
G01X169400Y294328D02*
Y288128D01*
X172600D01*
Y294328D01*
X169400D01*
G01X150820Y294292D02*
Y288092D01*
X154020D01*
Y294292D01*
X150820D01*
G01X154820D02*
Y288092D01*
X158020D01*
Y294292D01*
X154820D01*
G01X158900Y294328D02*
Y288128D01*
X162100D01*
Y294328D01*
X158900D01*
G01X168600Y288128D02*
Y294328D01*
X165400D01*
Y288128D01*
X168600D01*
G01X152133Y302825D02*
X152293Y303117D01*
X152507Y303283D01*
X152747Y303325D01*
X152960Y303283D01*
X153173Y303075D01*
X153307Y302825D01*
X153333Y302575D01*
X153280Y302283D01*
X153093Y302075D01*
X152907Y301992D01*
X152667D01*
G01X152907D02*
X153067Y301867D01*
X153200Y301658D01*
X153253Y301408D01*
X153200Y301158D01*
X153067Y300950D01*
X152827Y300825D01*
X152587Y300867D01*
X152347Y301033D01*
G01X154920Y300825D02*
X154707Y300908D01*
X154547Y301117D01*
X154440Y301367D01*
X154360Y301700D01*
X154333Y302075D01*
X154360Y302450D01*
X154440Y302783D01*
X154547Y303033D01*
X154707Y303242D01*
X154920Y303325D01*
X155133Y303242D01*
X155293Y303033D01*
X155400Y302783D01*
X155480Y302450D01*
X155507Y302075D01*
X155480Y301700D01*
X155400Y301367D01*
X155293Y301117D01*
X155133Y300908D01*
X154920Y300825D01*
G01X164633Y300592D02*
Y302592D01*
G01X156759Y298592D02*
Y302592D01*
G01X155381Y316892D02*
Y317792D01*
G01Y310592D02*
Y314592D01*
G01Y307292D02*
Y308292D01*
G01X155820Y304153D02*
X155381D01*
Y305392D01*
G01X165500Y336983D02*
X168600D01*
Y337903D01*
X168445Y338210D01*
X168083Y338440D01*
X167670Y338517D01*
X167257Y338440D01*
X166947Y338248D01*
X166792Y337903D01*
Y336983D01*
G01X165500Y340007D02*
X168600D01*
Y340773D01*
X168445Y341080D01*
X168238Y341310D01*
X167928Y341502D01*
X167567Y341655D01*
X167050Y341693D01*
X166533Y341655D01*
X166172Y341502D01*
X165862Y341310D01*
X165655Y341080D01*
X165500Y340773D01*
Y340007D01*
G01X165862Y343298D02*
X165603Y343567D01*
X165500Y343873D01*
X165603Y344180D01*
X165913Y344448D01*
X166378Y344640D01*
X166843Y344717D01*
X167412D01*
X167877Y344640D01*
X168290Y344448D01*
X168497Y344218D01*
X168600Y343950D01*
X168497Y343643D01*
X168290Y343413D01*
X167980Y343260D01*
X167567Y343183D01*
X167205Y343260D01*
X166843Y343452D01*
X166637Y343682D01*
X166585Y343950D01*
X166688Y344257D01*
X166947Y344487D01*
X167412Y344717D01*
G01X169614Y374792D02*
Y336792D01*
X181858D01*
G01X155340Y327725D02*
Y325225D01*
X154353Y327017D01*
X155687D01*
G01X153053Y319479D02*
X153345Y319319D01*
X153511Y319105D01*
X153553Y318865D01*
X153511Y318652D01*
X153303Y318439D01*
X153053Y318305D01*
X152803Y318279D01*
X152511Y318332D01*
X152303Y318519D01*
X152220Y318705D01*
Y318945D01*
G01Y318705D02*
X152095Y318545D01*
X151886Y318412D01*
X151636Y318359D01*
X151386Y318412D01*
X151178Y318545D01*
X151053Y318785D01*
X151095Y319025D01*
X151261Y319265D01*
G01X166207Y325792D02*
Y329792D01*
G01X158333Y325792D02*
Y327792D01*
G01X155381Y322992D02*
Y324231D01*
X155820D01*
G01X155381Y320092D02*
Y321092D01*
G01X169614Y376292D02*
X194102D01*
G01X169614Y375592D02*
X194102D01*
G01X169614Y375192D02*
X194102D01*
G01X169614Y375992D02*
X194102D01*
G01X169614Y376792D02*
Y374742D01*
G01X181858Y374792D02*
X169614D01*
G01Y376792D02*
X181858D01*
G01X152165Y394429D02*
Y485177D01*
X194291D01*
Y394429D01*
X152165D01*
G01X182086Y435078D02*
Y406634D01*
X164370D01*
G01D02*
Y472972D01*
X169410D01*
G01X157900Y496900D02*
X164100D01*
Y500100D01*
X157900D01*
Y496900D01*
G01Y501400D02*
X164100D01*
Y504600D01*
X157900D01*
Y501400D01*
G01Y505900D02*
X164100D01*
Y509100D01*
X157900D01*
Y505900D01*
G01Y510400D02*
X164100D01*
Y513600D01*
X157900D01*
Y510400D01*
G01Y514900D02*
X164100D01*
Y518100D01*
X157900D01*
Y514900D01*
G01Y523900D02*
X164100D01*
Y527100D01*
X157900D01*
Y523900D01*
G01Y519400D02*
X164100D01*
Y522600D01*
X157900D01*
Y519400D01*
G01Y528400D02*
X164100D01*
Y531600D01*
X157900D01*
Y528400D01*
G01X152165Y757815D02*
Y848563D01*
X194291D01*
Y757815D01*
X152165D01*
G01X182086Y798464D02*
Y770020D01*
X164370D01*
G01D02*
Y836358D01*
X169410D01*
G01X160117Y876700D02*
Y879800D01*
X159197D01*
X158890Y879645D01*
X158660Y879283D01*
X158583Y878870D01*
X158660Y878457D01*
X158852Y878147D01*
X159197Y877992D01*
X160117D01*
G01X157093Y876700D02*
Y879800D01*
X156327D01*
X156020Y879645D01*
X155790Y879438D01*
X155598Y879128D01*
X155445Y878767D01*
X155407Y878250D01*
X155445Y877733D01*
X155598Y877372D01*
X155790Y877062D01*
X156020Y876855D01*
X156327Y876700D01*
X157093D01*
G01X153150D02*
X152882Y876752D01*
X152575Y876907D01*
X152383Y877165D01*
X152307Y877527D01*
X152383Y877888D01*
X152613Y878198D01*
X152958Y878353D01*
X153342D01*
X153572Y878457D01*
X153763Y878715D01*
X153840Y879077D01*
X153725Y879438D01*
X153457Y879697D01*
X153150Y879800D01*
X152843Y879697D01*
X152575Y879438D01*
X152460Y879077D01*
X152537Y878715D01*
X152728Y878457D01*
X152958Y878353D01*
X153342D01*
X153687Y878198D01*
X153917Y877888D01*
X153993Y877527D01*
X153917Y877165D01*
X153725Y876907D01*
X153418Y876752D01*
X153150Y876700D01*
G01X169000Y893200D02*
X177500Y897200D01*
Y889200D01*
X169500Y893200D01*
G01X153000Y880956D02*
Y905444D01*
G01X153700Y880956D02*
Y905444D01*
G01X154100Y880956D02*
Y905444D01*
G01X153300Y880956D02*
Y905444D01*
G01X152500Y880956D02*
X154550D01*
G01X192500Y893200D02*
Y905444D01*
X154500D01*
Y893200D01*
G01D02*
Y880956D01*
G01X152500Y893200D02*
Y905444D01*
G01X154500Y880956D02*
X192500D01*
Y893200D01*
G01X169000D02*
X166400D01*
G01X169000Y887700D02*
Y898700D01*
G01X152500Y880956D02*
Y893200D01*
G01X154550Y905444D02*
X152450D01*
G01X182200Y908300D02*
Y915700D01*
X164800D01*
Y908300D01*
X182200D01*
G01X181677Y938600D02*
Y944600D01*
X169677D01*
Y938600D01*
X181677D01*
G01X182200Y929072D02*
Y936472D01*
X164800D01*
Y929072D01*
X182200D01*
G01Y918800D02*
Y926200D01*
X164800D01*
Y918800D01*
X182200D01*
G01X169258Y975149D02*
X163258D01*
Y963149D01*
X169258D01*
Y975149D01*
G01X167117Y951500D02*
Y954600D01*
X166197D01*
X165890Y954445D01*
X165660Y954083D01*
X165583Y953670D01*
X165660Y953257D01*
X165852Y952947D01*
X166197Y952792D01*
X167117D01*
G01X164093Y954600D02*
Y952378D01*
X163940Y951913D01*
X163633Y951603D01*
X163250Y951500D01*
X162867Y951603D01*
X162560Y951913D01*
X162407Y952378D01*
Y954600D01*
G01X159690Y951500D02*
Y954600D01*
X161108Y952378D01*
X159192D01*
G01X157000Y948652D02*
Y951152D01*
X157987Y949360D01*
X156653D01*
G01X159287Y956898D02*
X158995Y957058D01*
X158829Y957272D01*
X158787Y957512D01*
X158829Y957725D01*
X159037Y957938D01*
X159287Y958072D01*
X159537Y958098D01*
X159829Y958045D01*
X160037Y957858D01*
X160120Y957672D01*
Y957432D01*
G01Y957672D02*
X160245Y957832D01*
X160454Y957965D01*
X160704Y958018D01*
X160954Y957965D01*
X161162Y957832D01*
X161287Y957592D01*
X161245Y957352D01*
X161079Y957112D01*
G01X154007Y950585D02*
Y948585D01*
G01X156959Y953385D02*
Y952146D01*
X156520D01*
G01X156959Y956285D02*
Y955285D01*
G01Y959485D02*
Y958585D01*
G01Y965785D02*
Y961785D01*
G01X160207Y973552D02*
X160047Y973260D01*
X159833Y973094D01*
X159593Y973052D01*
X159380Y973094D01*
X159167Y973302D01*
X159033Y973552D01*
X159007Y973802D01*
X159060Y974094D01*
X159247Y974302D01*
X159433Y974385D01*
X159673D01*
G01X159433D02*
X159273Y974510D01*
X159140Y974719D01*
X159087Y974969D01*
X159140Y975219D01*
X159273Y975427D01*
X159513Y975552D01*
X159753Y975510D01*
X159993Y975344D01*
G01X157420Y975552D02*
X157633Y975469D01*
X157793Y975260D01*
X157900Y975010D01*
X157980Y974677D01*
X158007Y974302D01*
X157980Y973927D01*
X157900Y973594D01*
X157793Y973344D01*
X157633Y973135D01*
X157420Y973052D01*
X157207Y973135D01*
X157047Y973344D01*
X156940Y973594D01*
X156860Y973927D01*
X156833Y974302D01*
X156860Y974677D01*
X156940Y975010D01*
X157047Y975260D01*
X157207Y975469D01*
X157420Y975552D01*
G01X147707Y975785D02*
Y973785D01*
G01X155581Y977785D02*
Y973785D01*
G01X156959Y969085D02*
Y968085D01*
G01X156520Y972224D02*
X156959D01*
Y970985D01*
G01X163520Y982085D02*
Y988285D01*
X160320D01*
Y982085D01*
X163520D01*
G01X159520D02*
Y988285D01*
X156320D01*
Y982085D01*
X159520D01*
G01X155100D02*
Y988285D01*
X151900D01*
Y982085D01*
X155100D01*
G01X167600D02*
Y988285D01*
X164400D01*
Y982085D01*
X167600D01*
G01X150658Y1003100D02*
X164058D01*
G01D02*
Y1011900D01*
G01X150658D02*
Y1003100D01*
G01X156358Y1011900D02*
X157358Y1010300D01*
X158358Y1011900D01*
G01X170200Y990007D02*
X167978D01*
X167513Y990160D01*
X167203Y990467D01*
X167100Y990850D01*
X167203Y991233D01*
X167513Y991540D01*
X167978Y991693D01*
X170200D01*
G01X167720Y993107D02*
X167358Y993337D01*
X167152Y993643D01*
X167100Y993988D01*
X167152Y994295D01*
X167410Y994602D01*
X167720Y994793D01*
X168030Y994832D01*
X168392Y994755D01*
X168650Y994487D01*
X168753Y994218D01*
Y993873D01*
G01Y994218D02*
X168908Y994448D01*
X169167Y994640D01*
X169477Y994717D01*
X169787Y994640D01*
X170045Y994448D01*
X170200Y994103D01*
X170148Y993758D01*
X169942Y993413D01*
G01X167100Y996973D02*
X167772Y997050D01*
X168340Y997165D01*
X168857Y997318D01*
X169425Y997510D01*
X170200Y997817D01*
Y996283D01*
G01X167462Y999498D02*
X167203Y999767D01*
X167100Y1000073D01*
X167203Y1000380D01*
X167513Y1000648D01*
X167978Y1000840D01*
X168443Y1000917D01*
X169012D01*
X169477Y1000840D01*
X169890Y1000648D01*
X170097Y1000418D01*
X170200Y1000150D01*
X170097Y999843D01*
X169890Y999613D01*
X169580Y999460D01*
X169167Y999383D01*
X168805Y999460D01*
X168443Y999652D01*
X168237Y999882D01*
X168185Y1000150D01*
X168288Y1000457D01*
X168547Y1000687D01*
X169012Y1000917D01*
G01X161682Y1000049D02*
X148282D01*
G01X153982Y991249D02*
X148282D01*
G01X161682D02*
X155982D01*
G01X148282Y1000049D02*
Y991249D01*
G01X161682D02*
Y1000049D01*
G01X155982Y991249D02*
X154982Y992849D01*
X153982Y991249D01*
G01X158358Y1011900D02*
X164058D01*
G01X150658D02*
X156358D01*
G01X155687Y1028000D02*
X155527Y1027708D01*
X155313Y1027542D01*
X155073Y1027500D01*
X154860Y1027542D01*
X154647Y1027750D01*
X154513Y1028000D01*
X154487Y1028250D01*
X154540Y1028542D01*
X154727Y1028750D01*
X154913Y1028833D01*
X155153D01*
G01X154913D02*
X154753Y1028958D01*
X154620Y1029167D01*
X154567Y1029417D01*
X154620Y1029667D01*
X154753Y1029875D01*
X154993Y1030000D01*
X155233Y1029958D01*
X155473Y1029792D01*
G01X152900Y1030000D02*
X153113Y1029917D01*
X153273Y1029708D01*
X153380Y1029458D01*
X153460Y1029125D01*
X153487Y1028750D01*
X153460Y1028375D01*
X153380Y1028042D01*
X153273Y1027792D01*
X153113Y1027583D01*
X152900Y1027500D01*
X152687Y1027583D01*
X152527Y1027792D01*
X152420Y1028042D01*
X152340Y1028375D01*
X152313Y1028750D01*
X152340Y1029125D01*
X152420Y1029458D01*
X152527Y1029708D01*
X152687Y1029917D01*
X152900Y1030000D01*
G01X164633Y1027364D02*
Y1029364D01*
G01X156759Y1025364D02*
Y1029364D01*
G01X155820Y1030925D02*
X155381D01*
Y1032164D01*
G01X163900Y1021100D02*
Y1014900D01*
X167100D01*
Y1021100D01*
X163900D01*
G01X149820Y1021064D02*
Y1014864D01*
X153020D01*
Y1021064D01*
X149820D01*
G01X153820D02*
Y1014864D01*
X157020D01*
Y1021064D01*
X153820D01*
G01X157900Y1021100D02*
Y1014900D01*
X161100D01*
Y1021100D01*
X157900D01*
G01X171100Y1014900D02*
Y1021100D01*
X167900D01*
Y1014900D01*
X171100D01*
G01X154680Y1052000D02*
Y1054500D01*
X155667Y1052708D01*
X154333D01*
G01X151500Y1044913D02*
X151208Y1045073D01*
X151042Y1045287D01*
X151000Y1045527D01*
X151042Y1045740D01*
X151250Y1045953D01*
X151500Y1046087D01*
X151750Y1046113D01*
X152042Y1046060D01*
X152250Y1045873D01*
X152333Y1045687D01*
Y1045447D01*
G01Y1045687D02*
X152458Y1045847D01*
X152667Y1045980D01*
X152917Y1046033D01*
X153167Y1045980D01*
X153375Y1045847D01*
X153500Y1045607D01*
X153458Y1045367D01*
X153292Y1045127D01*
G01X166207Y1052564D02*
Y1056564D01*
G01X155381Y1049764D02*
Y1051003D01*
X155820D01*
G01X155381Y1046864D02*
Y1047864D01*
G01Y1043664D02*
Y1044564D01*
G01Y1037364D02*
Y1041364D01*
G01Y1034064D02*
Y1035064D01*
G01X175000Y1061927D02*
Y1059687D01*
G01X173375Y1060900D02*
X176625D01*
G01X152165Y1121201D02*
Y1211949D01*
X194291D01*
Y1121201D01*
X152165D01*
G01X182086Y1161850D02*
Y1133406D01*
X164370D01*
G01D02*
Y1199744D01*
X169410D01*
G01X177047Y109586D02*
X182086D01*
Y81142D01*
G01Y71692D02*
X194291D01*
G01X182086Y81142D02*
X194291D01*
G01X194045Y124137D02*
X193853Y123827D01*
X193623Y123620D01*
X193355Y123517D01*
X193048Y123620D01*
X192818Y123827D01*
X192588Y124137D01*
X192511Y124550D01*
Y126617D01*
G01X189718Y123517D02*
Y126617D01*
X191136Y124395D01*
X189220D01*
G01X188217Y152900D02*
Y156000D01*
X187297D01*
X186990Y155845D01*
X186760Y155483D01*
X186683Y155070D01*
X186760Y154657D01*
X186952Y154347D01*
X187297Y154192D01*
X188217D01*
G01X185193Y152900D02*
Y156000D01*
X184427D01*
X184120Y155845D01*
X183890Y155638D01*
X183698Y155328D01*
X183545Y154967D01*
X183507Y154450D01*
X183545Y153933D01*
X183698Y153572D01*
X183890Y153262D01*
X184120Y153055D01*
X184427Y152900D01*
X185193D01*
G01X181250D02*
Y156000D01*
X181710Y155380D01*
G01Y152900D02*
X180790D01*
G01X178150Y156000D02*
X178457Y155897D01*
X178687Y155638D01*
X178840Y155328D01*
X178955Y154915D01*
X178993Y154450D01*
X178955Y153985D01*
X178840Y153572D01*
X178687Y153262D01*
X178457Y153003D01*
X178150Y152900D01*
X177843Y153003D01*
X177613Y153262D01*
X177460Y153572D01*
X177345Y153985D01*
X177307Y154450D01*
X177345Y154915D01*
X177460Y155328D01*
X177613Y155638D01*
X177843Y155897D01*
X178150Y156000D01*
G01X193273Y168800D02*
X195513D01*
G01X194300Y167175D02*
Y170425D01*
G01X173900Y169628D02*
X176300D01*
G01X187500Y226913D02*
Y224487D01*
G01X195202Y268424D02*
Y228332D01*
X170714D01*
Y268424D01*
X195202D01*
G01X182458Y247628D02*
Y244628D01*
G01X178458Y247128D02*
X186458D01*
G01X179458Y252628D02*
X185458D01*
X182458Y247628D01*
X179458Y252628D01*
G01X182558Y272455D02*
Y270215D01*
G01X180933Y271428D02*
X184183D01*
G01X182458Y255628D02*
Y252628D01*
G01X189300Y275107D02*
X187078D01*
X186613Y275260D01*
X186303Y275567D01*
X186200Y275950D01*
X186303Y276333D01*
X186613Y276640D01*
X187078Y276793D01*
X189300D01*
G01X186820Y278207D02*
X186458Y278437D01*
X186252Y278743D01*
X186200Y279088D01*
X186252Y279395D01*
X186510Y279702D01*
X186820Y279893D01*
X187130Y279932D01*
X187492Y279855D01*
X187750Y279587D01*
X187853Y279318D01*
Y278973D01*
G01Y279318D02*
X188008Y279548D01*
X188267Y279740D01*
X188577Y279817D01*
X188887Y279740D01*
X189145Y279548D01*
X189300Y279203D01*
X189248Y278858D01*
X189042Y278513D01*
G01X186562Y281498D02*
X186303Y281767D01*
X186200Y282073D01*
X186303Y282380D01*
X186613Y282648D01*
X187078Y282840D01*
X187543Y282917D01*
X188112D01*
X188577Y282840D01*
X188990Y282648D01*
X189197Y282418D01*
X189300Y282150D01*
X189197Y281843D01*
X188990Y281613D01*
X188680Y281460D01*
X188267Y281383D01*
X187905Y281460D01*
X187543Y281652D01*
X187337Y281882D01*
X187285Y282150D01*
X187388Y282457D01*
X187647Y282687D01*
X188112Y282917D01*
G01X187492Y284522D02*
X187853Y284790D01*
X188060Y285020D01*
X188163Y285327D01*
X188060Y285595D01*
X187853Y285787D01*
X187543Y285940D01*
X187182Y285978D01*
X186872Y285940D01*
X186562Y285787D01*
X186303Y285557D01*
X186200Y285288D01*
X186303Y284982D01*
X186613Y284713D01*
X187078Y284560D01*
X187595Y284522D01*
X188267Y284598D01*
X188628Y284713D01*
X188990Y284905D01*
X189248Y285173D01*
X189300Y285442D01*
X189197Y285710D01*
X188938Y285902D01*
G01X171158Y274928D02*
Y285528D01*
X180558D01*
Y274928D01*
X171258D01*
G01X184600Y288128D02*
Y294328D01*
X181400D01*
Y288128D01*
X184600D01*
G01X185400Y294328D02*
Y288128D01*
X188600D01*
Y294328D01*
X185400D01*
G01X173400D02*
Y288128D01*
X176600D01*
Y294328D01*
X173400D01*
G01X177400D02*
Y288128D01*
X180600D01*
Y294328D01*
X177400D01*
G01X187117Y303500D02*
Y306600D01*
X186197D01*
X185890Y306445D01*
X185660Y306083D01*
X185583Y305670D01*
X185660Y305257D01*
X185852Y304947D01*
X186197Y304792D01*
X187117D01*
G01X184093Y306600D02*
Y304378D01*
X183940Y303913D01*
X183633Y303603D01*
X183250Y303500D01*
X182867Y303603D01*
X182560Y303913D01*
X182407Y304378D01*
Y306600D01*
G01X180993Y303965D02*
X180763Y303707D01*
X180495Y303552D01*
X180150Y303500D01*
X179805Y303603D01*
X179537Y303810D01*
X179345Y304172D01*
X179307Y304585D01*
X179383Y304998D01*
X179575Y305257D01*
X179843Y305463D01*
X180112Y305515D01*
X180380Y305463D01*
X180725Y305257D01*
X180610Y306600D01*
X179575D01*
G01X175520Y303125D02*
Y300625D01*
X175200Y301125D01*
G01Y303125D02*
X175840D01*
G01X177267Y302833D02*
X177453Y303042D01*
X177667Y303125D01*
X177880Y303042D01*
X178067Y302792D01*
X178200Y302417D01*
X178253Y302042D01*
Y301583D01*
X178200Y301208D01*
X178067Y300875D01*
X177907Y300708D01*
X177720Y300625D01*
X177507Y300708D01*
X177347Y300875D01*
X177240Y301125D01*
X177187Y301458D01*
X177240Y301750D01*
X177373Y302042D01*
X177533Y302208D01*
X177720Y302250D01*
X177933Y302167D01*
X178093Y301958D01*
X178253Y301583D01*
G01X179553Y310492D02*
X177053D01*
X177553Y310812D01*
G01X179553D02*
Y310172D01*
G01Y308292D02*
X179511Y308105D01*
X179386Y307892D01*
X179178Y307759D01*
X178886Y307705D01*
X178595Y307759D01*
X178345Y307919D01*
X178220Y308159D01*
Y308425D01*
X178136Y308585D01*
X177928Y308719D01*
X177636Y308772D01*
X177345Y308692D01*
X177136Y308505D01*
X177053Y308292D01*
X177136Y308079D01*
X177345Y307892D01*
X177636Y307812D01*
X177928Y307865D01*
X178136Y307999D01*
X178220Y308159D01*
Y308425D01*
X178345Y308665D01*
X178595Y308825D01*
X178886Y308879D01*
X179178Y308825D01*
X179386Y308692D01*
X179511Y308479D01*
X179553Y308292D01*
G01X179653Y320092D02*
X177153D01*
X177653Y320412D01*
G01X179653D02*
Y319772D01*
G01X178611Y318399D02*
X178320Y318212D01*
X178153Y318052D01*
X178070Y317839D01*
X178153Y317652D01*
X178320Y317519D01*
X178570Y317412D01*
X178861Y317385D01*
X179111Y317412D01*
X179361Y317519D01*
X179570Y317679D01*
X179653Y317865D01*
X179570Y318079D01*
X179320Y318265D01*
X178945Y318372D01*
X178528Y318399D01*
X177986Y318345D01*
X177695Y318265D01*
X177403Y318132D01*
X177195Y317945D01*
X177153Y317759D01*
X177236Y317572D01*
X177445Y317439D01*
G01X172507Y298592D02*
Y302592D01*
G01X175459Y305392D02*
Y304153D01*
G01Y308292D02*
Y307292D01*
G01Y311492D02*
Y310592D01*
G01Y317792D02*
Y313792D01*
G01Y304153D02*
X175020D01*
G01X189500Y335327D02*
Y333087D01*
G01X187875Y334300D02*
X191125D01*
G01X181858Y336792D02*
X194102D01*
Y374792D01*
X181858D01*
G01X175720Y327625D02*
Y325125D01*
X175400Y325625D01*
G01Y327625D02*
X176040D01*
G01X177333Y327250D02*
X177493Y327458D01*
X177680Y327583D01*
X177920Y327625D01*
X178160Y327542D01*
X178347Y327375D01*
X178480Y327083D01*
X178507Y326750D01*
X178453Y326417D01*
X178320Y326208D01*
X178133Y326042D01*
X177947Y326000D01*
X177760Y326042D01*
X177520Y326208D01*
X177600Y325125D01*
X178320D01*
G01X174081Y325792D02*
Y327792D01*
G01X175459Y321092D02*
Y320092D01*
G01X175020Y324231D02*
X175459D01*
Y322992D01*
G01X181858Y360292D02*
X185858Y351792D01*
X177858D01*
X181858Y359792D01*
G01Y351492D02*
Y349092D01*
G01Y360292D02*
Y362892D01*
G01X176358Y360292D02*
X187358D01*
G01X187500Y380513D02*
Y378087D01*
G01X181858Y376792D02*
X194102D01*
G01X177047Y472972D02*
X182086D01*
Y444528D01*
G01Y435078D02*
X194291D01*
G01X182086Y444528D02*
X194291D01*
G01X194617Y487120D02*
X194425Y486810D01*
X194195Y486603D01*
X193927Y486500D01*
X193620Y486603D01*
X193390Y486810D01*
X193160Y487120D01*
X193083Y487533D01*
Y489600D01*
G01X191593Y487120D02*
X191363Y486758D01*
X191057Y486552D01*
X190712Y486500D01*
X190405Y486552D01*
X190098Y486810D01*
X189907Y487120D01*
X189868Y487430D01*
X189945Y487792D01*
X190213Y488050D01*
X190482Y488153D01*
X190827D01*
G01X190482D02*
X190252Y488308D01*
X190060Y488567D01*
X189983Y488877D01*
X190060Y489187D01*
X190252Y489445D01*
X190597Y489600D01*
X190942Y489548D01*
X191287Y489342D01*
G01X182086Y798464D02*
X194291D01*
G01X177047Y836358D02*
X182086D01*
Y807914D01*
G01D02*
X194291D01*
G01X194045Y850909D02*
X193853Y850599D01*
X193623Y850392D01*
X193355Y850289D01*
X193048Y850392D01*
X192818Y850599D01*
X192588Y850909D01*
X192511Y851322D01*
Y853389D01*
G01X190906Y852872D02*
X190676Y853182D01*
X190408Y853337D01*
X190101Y853389D01*
X189718Y853286D01*
X189450Y853027D01*
X189373Y852717D01*
X189411Y852407D01*
X189565Y852149D01*
X190331Y851632D01*
X190676Y851271D01*
X190906Y850754D01*
X190983Y850289D01*
X189373D01*
G01X177800Y893200D02*
X180200D01*
G01X178500Y952413D02*
Y949987D01*
G01X196044Y993996D02*
Y953904D01*
X171556D01*
Y993996D01*
X196044D01*
G01X183300Y973200D02*
Y970200D01*
G01X179300Y972700D02*
X187300D01*
G01X180300Y978200D02*
X186300D01*
X183300Y973200D01*
X180300Y978200D01*
G01X183300Y981200D02*
Y978200D01*
G01X189100Y1000807D02*
X186878D01*
X186413Y1000960D01*
X186103Y1001267D01*
X186000Y1001650D01*
X186103Y1002033D01*
X186413Y1002340D01*
X186878Y1002493D01*
X189100D01*
G01X186620Y1003907D02*
X186258Y1004137D01*
X186052Y1004443D01*
X186000Y1004788D01*
X186052Y1005095D01*
X186310Y1005402D01*
X186620Y1005593D01*
X186930Y1005632D01*
X187292Y1005555D01*
X187550Y1005287D01*
X187653Y1005018D01*
Y1004673D01*
G01Y1005018D02*
X187808Y1005248D01*
X188067Y1005440D01*
X188377Y1005517D01*
X188687Y1005440D01*
X188945Y1005248D01*
X189100Y1004903D01*
X189048Y1004558D01*
X188842Y1004213D01*
G01X186362Y1007198D02*
X186103Y1007467D01*
X186000Y1007773D01*
X186103Y1008080D01*
X186413Y1008348D01*
X186878Y1008540D01*
X187343Y1008617D01*
X187912D01*
X188377Y1008540D01*
X188790Y1008348D01*
X188997Y1008118D01*
X189100Y1007850D01*
X188997Y1007543D01*
X188790Y1007313D01*
X188480Y1007160D01*
X188067Y1007083D01*
X187705Y1007160D01*
X187343Y1007352D01*
X187137Y1007582D01*
X187085Y1007850D01*
X187188Y1008157D01*
X187447Y1008387D01*
X187912Y1008617D01*
G01X186000Y1011410D02*
X189100D01*
X186878Y1009992D01*
Y1011908D01*
G01X171158Y1001700D02*
Y1012300D01*
X180558D01*
Y1001700D01*
X171258D01*
G01X177000Y997727D02*
Y995487D01*
G01X175375Y996700D02*
X178625D01*
G01X188117Y1030000D02*
Y1033100D01*
X187197D01*
X186890Y1032945D01*
X186660Y1032583D01*
X186583Y1032170D01*
X186660Y1031757D01*
X186852Y1031447D01*
X187197Y1031292D01*
X188117D01*
G01X185093Y1033100D02*
Y1030878D01*
X184940Y1030413D01*
X184633Y1030103D01*
X184250Y1030000D01*
X183867Y1030103D01*
X183560Y1030413D01*
X183407Y1030878D01*
Y1033100D01*
G01X181150Y1030000D02*
Y1033100D01*
X181610Y1032480D01*
G01Y1030000D02*
X180690D01*
G01X178600Y1027500D02*
Y1030000D01*
X178920Y1029500D01*
G01Y1027500D02*
X178280D01*
G01X176853Y1027792D02*
X176667Y1027583D01*
X176453Y1027500D01*
X176240Y1027583D01*
X176053Y1027833D01*
X175920Y1028208D01*
X175867Y1028583D01*
Y1029042D01*
X175920Y1029417D01*
X176053Y1029750D01*
X176213Y1029917D01*
X176400Y1030000D01*
X176613Y1029917D01*
X176773Y1029750D01*
X176880Y1029500D01*
X176933Y1029167D01*
X176880Y1028875D01*
X176747Y1028583D01*
X176587Y1028417D01*
X176400Y1028375D01*
X176187Y1028458D01*
X176027Y1028667D01*
X175867Y1029042D01*
G01X172507Y1025364D02*
Y1029364D01*
G01X175459Y1032164D02*
Y1030925D01*
G01D02*
X175020D01*
G01X183900Y1021100D02*
Y1014900D01*
X187100D01*
Y1021100D01*
X183900D01*
G01X183100Y1014900D02*
Y1021100D01*
X179900D01*
Y1014900D01*
X183100D01*
G01X171900Y1021100D02*
Y1014900D01*
X175100D01*
Y1021100D01*
X171900D01*
G01X175900D02*
Y1014900D01*
X179100D01*
Y1021100D01*
X175900D01*
G01X177500Y1034900D02*
X180000D01*
X179500Y1034580D01*
G01X177500D02*
Y1035220D01*
G01Y1037100D02*
X177542Y1037287D01*
X177667Y1037500D01*
X177875Y1037633D01*
X178167Y1037687D01*
X178458Y1037633D01*
X178708Y1037473D01*
X178833Y1037233D01*
Y1036967D01*
X178917Y1036807D01*
X179125Y1036673D01*
X179417Y1036620D01*
X179708Y1036700D01*
X179917Y1036887D01*
X180000Y1037100D01*
X179917Y1037313D01*
X179708Y1037500D01*
X179417Y1037580D01*
X179125Y1037527D01*
X178917Y1037393D01*
X178833Y1037233D01*
Y1036967D01*
X178708Y1036727D01*
X178458Y1036567D01*
X178167Y1036513D01*
X177875Y1036567D01*
X177667Y1036700D01*
X177542Y1036913D01*
X177500Y1037100D01*
G01Y1044400D02*
X180000D01*
X179500Y1044080D01*
G01X177500D02*
Y1044720D01*
G01X178542Y1046093D02*
X178833Y1046280D01*
X179000Y1046440D01*
X179083Y1046653D01*
X179000Y1046840D01*
X178833Y1046973D01*
X178583Y1047080D01*
X178292Y1047107D01*
X178042Y1047080D01*
X177792Y1046973D01*
X177583Y1046813D01*
X177500Y1046627D01*
X177583Y1046413D01*
X177833Y1046227D01*
X178208Y1046120D01*
X178625Y1046093D01*
X179167Y1046147D01*
X179458Y1046227D01*
X179750Y1046360D01*
X179958Y1046547D01*
X180000Y1046733D01*
X179917Y1046920D01*
X179708Y1047053D01*
G01X178100Y1052000D02*
Y1054500D01*
X178420Y1054000D01*
G01Y1052000D02*
X177780D01*
G01X176487Y1052375D02*
X176327Y1052167D01*
X176140Y1052042D01*
X175900Y1052000D01*
X175660Y1052083D01*
X175473Y1052250D01*
X175340Y1052542D01*
X175313Y1052875D01*
X175367Y1053208D01*
X175500Y1053417D01*
X175687Y1053583D01*
X175873Y1053625D01*
X176060Y1053583D01*
X176300Y1053417D01*
X176220Y1054500D01*
X175500D01*
G01X174081Y1052564D02*
Y1054564D01*
G01X175459Y1035064D02*
Y1034064D01*
G01Y1038264D02*
Y1037364D01*
G01Y1044564D02*
Y1040564D01*
G01Y1047864D02*
Y1046864D01*
G01X175020Y1051003D02*
X175459D01*
Y1049764D01*
G01X183800Y1087100D02*
X187800Y1078600D01*
X179800D01*
X183800Y1086600D01*
G01Y1063600D02*
X196044D01*
Y1101600D01*
X183800D01*
G01X171556D02*
Y1063600D01*
X183800D01*
G01Y1078300D02*
Y1075900D01*
G01X171556Y1102400D02*
X196044D01*
G01X171556Y1102000D02*
X196044D01*
G01X171556Y1102800D02*
X196044D01*
G01X171556Y1103600D02*
Y1101550D01*
G01X183800Y1101600D02*
X171556D01*
G01X183800Y1087100D02*
Y1089700D01*
G01X178300Y1087100D02*
X189300D01*
G01X184200Y1110313D02*
Y1107887D01*
G01X171556Y1103100D02*
X196044D01*
G01X183800Y1103600D02*
X196044D01*
G01X171556D02*
X183800D01*
G01X177047Y1199744D02*
X182086D01*
Y1171300D01*
G01Y1161850D02*
X194291D01*
G01X182086Y1171300D02*
X194291D01*
G01X191117Y1214120D02*
X190925Y1213810D01*
X190695Y1213603D01*
X190427Y1213500D01*
X190120Y1213603D01*
X189890Y1213810D01*
X189660Y1214120D01*
X189583Y1214533D01*
Y1216600D01*
G01X187250Y1213500D02*
Y1216600D01*
X187710Y1215980D01*
G01Y1213500D02*
X186790D01*
G01X178300Y1228900D02*
Y1239100D01*
X173700D01*
Y1228900D01*
X178300D01*
G01X196100Y228783D02*
X199200D01*
Y229703D01*
X199045Y230010D01*
X198683Y230240D01*
X198270Y230317D01*
X197857Y230240D01*
X197547Y230048D01*
X197392Y229703D01*
Y228783D01*
G01X196100Y231807D02*
X199200D01*
Y232573D01*
X199045Y232880D01*
X198838Y233110D01*
X198528Y233302D01*
X198167Y233455D01*
X197650Y233493D01*
X197133Y233455D01*
X196772Y233302D01*
X196462Y233110D01*
X196255Y232880D01*
X196100Y232573D01*
Y231807D01*
G01Y235750D02*
X199200D01*
X198580Y235290D01*
G01X196100D02*
Y236210D01*
G01Y239310D02*
X199200D01*
X196978Y237892D01*
Y239808D01*
G01X194102Y374742D02*
Y376842D01*
G01X195773Y891500D02*
X198013D01*
G01X196800Y889875D02*
Y893125D01*
G01X197700Y954283D02*
X200800D01*
Y955203D01*
X200645Y955510D01*
X200283Y955740D01*
X199870Y955817D01*
X199457Y955740D01*
X199147Y955548D01*
X198992Y955203D01*
Y954283D01*
G01X197700Y957307D02*
X200800D01*
Y958073D01*
X200645Y958380D01*
X200438Y958610D01*
X200128Y958802D01*
X199767Y958955D01*
X199250Y958993D01*
X198733Y958955D01*
X198372Y958802D01*
X198062Y958610D01*
X197855Y958380D01*
X197700Y958073D01*
Y957307D01*
G01Y961710D02*
X200800D01*
X198578Y960292D01*
Y962208D01*
G01X197167Y1064183D02*
X200267D01*
Y1065103D01*
X200112Y1065410D01*
X199750Y1065640D01*
X199337Y1065717D01*
X198924Y1065640D01*
X198614Y1065448D01*
X198459Y1065103D01*
Y1064183D01*
G01X197167Y1067207D02*
X200267D01*
Y1067973D01*
X200112Y1068280D01*
X199905Y1068510D01*
X199595Y1068702D01*
X199234Y1068855D01*
X198717Y1068893D01*
X198200Y1068855D01*
X197839Y1068702D01*
X197529Y1068510D01*
X197322Y1068280D01*
X197167Y1067973D01*
Y1067207D01*
G01Y1071150D02*
X200267D01*
X199647Y1070690D01*
G01X197167D02*
Y1071610D01*
G01X196044Y1101550D02*
Y1103650D01*
G01X331395Y-304184D02*
X330925Y-303869D01*
X330377Y-303659D01*
X329750D01*
X329045Y-303974D01*
X328497Y-304499D01*
X328105Y-305129D01*
X327792Y-306179D01*
X327714Y-307124D01*
X327870Y-308069D01*
X328105Y-308699D01*
X328575Y-309329D01*
X329124Y-309749D01*
X329672Y-309959D01*
X330220D01*
X330769Y-309749D01*
X331239Y-309434D01*
X331630Y-309014D01*
G01X335032Y-303659D02*
X336912D01*
G01X335972D02*
Y-309959D01*
G01X335032D02*
X336912D01*
G01X342272Y-303659D02*
Y-309959D01*
G01X340470Y-303659D02*
X344074D01*
G01X348572Y-309959D02*
Y-307124D01*
X347005Y-303659D01*
G01X350139D02*
X348572Y-307124D01*
G01X359449Y-308699D02*
X359919Y-309434D01*
X360545Y-309854D01*
X361250Y-309959D01*
X361877Y-309854D01*
X362504Y-309329D01*
X362895Y-308699D01*
X362974Y-308069D01*
X362817Y-307334D01*
X362269Y-306809D01*
X361720Y-306599D01*
X361015D01*
G01X361720D02*
X362190Y-306284D01*
X362582Y-305759D01*
X362739Y-305129D01*
X362582Y-304499D01*
X362190Y-303974D01*
X361485Y-303659D01*
X360780Y-303764D01*
X360075Y-304184D01*
G01X365749Y-308699D02*
X366219Y-309434D01*
X366845Y-309854D01*
X367550Y-309959D01*
X368177Y-309854D01*
X368804Y-309329D01*
X369195Y-308699D01*
X369274Y-308069D01*
X369117Y-307334D01*
X368569Y-306809D01*
X368020Y-306599D01*
X367315D01*
G01X368020D02*
X368490Y-306284D01*
X368882Y-305759D01*
X369039Y-305129D01*
X368882Y-304499D01*
X368490Y-303974D01*
X367785Y-303659D01*
X367080Y-303764D01*
X366375Y-304184D01*
G01X372049Y-308699D02*
X372519Y-309434D01*
X373145Y-309854D01*
X373850Y-309959D01*
X374477Y-309854D01*
X375104Y-309329D01*
X375495Y-308699D01*
X375574Y-308069D01*
X375417Y-307334D01*
X374869Y-306809D01*
X374320Y-306599D01*
X373615D01*
G01X374320D02*
X374790Y-306284D01*
X375182Y-305759D01*
X375339Y-305129D01*
X375182Y-304499D01*
X374790Y-303974D01*
X374085Y-303659D01*
X373380Y-303764D01*
X372675Y-304184D01*
G01X379915Y-309959D02*
X380072Y-308594D01*
X380307Y-307439D01*
X380620Y-306389D01*
X381012Y-305234D01*
X381639Y-303659D01*
X378505D01*
G01X386215Y-309959D02*
X386372Y-308594D01*
X386607Y-307439D01*
X386920Y-306389D01*
X387312Y-305234D01*
X387939Y-303659D01*
X384805D01*
G01X392515Y-311114D02*
X392829Y-309749D01*
G01X398972Y-303659D02*
Y-309959D01*
G01X397170Y-303659D02*
X400774D01*
G01X403314Y-309959D02*
X405272Y-303659D01*
X407230Y-309959D01*
G01X406525Y-307754D02*
X404019D01*
G01X410632Y-303659D02*
X412512D01*
G01X411572D02*
Y-309959D01*
G01X410632D02*
X412512D01*
G01X415522Y-303659D02*
X416619Y-309959D01*
X417872Y-303659D01*
X419125Y-309959D01*
X420222Y-303659D01*
G01X422214Y-309959D02*
X424172Y-303659D01*
X426130Y-309959D01*
G01X425425Y-307754D02*
X422919D01*
G01X428670Y-309959D02*
Y-303659D01*
X432274Y-309959D01*
Y-303659D01*
G01X442680Y-312059D02*
X441897Y-311009D01*
X441505Y-309959D01*
Y-305759D01*
X441897Y-304709D01*
X442680Y-303659D01*
G01X454105Y-309959D02*
Y-303659D01*
X456064D01*
X456690Y-303974D01*
X457082Y-304394D01*
X457239Y-305234D01*
X457082Y-306074D01*
X456612Y-306599D01*
X456064Y-306914D01*
X454105D01*
G01X456064D02*
X457239Y-309959D01*
G01X461972Y-310169D02*
X461815Y-310064D01*
Y-309854D01*
X461972Y-309749D01*
X462129Y-309854D01*
Y-310064D01*
X461972Y-310169D01*
G01X468272Y-309959D02*
X467645Y-309854D01*
X467097Y-309434D01*
X466627Y-308804D01*
X466314Y-308069D01*
X466157Y-307229D01*
Y-306389D01*
X466314Y-305549D01*
X466627Y-304814D01*
X467097Y-304184D01*
X467645Y-303764D01*
X468272Y-303659D01*
X468899Y-303764D01*
X469447Y-304184D01*
X469917Y-304814D01*
X470230Y-305549D01*
X470387Y-306389D01*
Y-307229D01*
X470230Y-308069D01*
X469917Y-308804D01*
X469447Y-309434D01*
X468899Y-309854D01*
X468272Y-309959D01*
G01X474572Y-310169D02*
X474415Y-310064D01*
Y-309854D01*
X474572Y-309749D01*
X474729Y-309854D01*
Y-310064D01*
X474572Y-310169D01*
G01X482595Y-304184D02*
X482125Y-303869D01*
X481577Y-303659D01*
X480950D01*
X480245Y-303974D01*
X479697Y-304499D01*
X479305Y-305129D01*
X478992Y-306179D01*
X478914Y-307124D01*
X479070Y-308069D01*
X479305Y-308699D01*
X479775Y-309329D01*
X480324Y-309749D01*
X480872Y-309959D01*
X481420D01*
X481969Y-309749D01*
X482439Y-309434D01*
X482830Y-309014D01*
G01X487172Y-310169D02*
X487015Y-310064D01*
Y-309854D01*
X487172Y-309749D01*
X487329Y-309854D01*
Y-310064D01*
X487172Y-310169D01*
G01X493864Y-312059D02*
X494647Y-311009D01*
X495039Y-309959D01*
Y-305759D01*
X494647Y-304709D01*
X493864Y-303659D01*
G01X330142Y-296809D02*
X331709D01*
Y-298699D01*
X331239Y-299329D01*
X330690Y-299749D01*
X329907Y-299959D01*
X329124Y-299749D01*
X328575Y-299329D01*
X328105Y-298699D01*
X327792Y-297964D01*
X327635Y-297124D01*
Y-296389D01*
X327792Y-295759D01*
X328105Y-295024D01*
X328575Y-294394D01*
X329045Y-293974D01*
X329672Y-293659D01*
X330220D01*
X330847Y-293869D01*
X331317Y-294289D01*
G01X334249Y-293659D02*
Y-298174D01*
X334562Y-299119D01*
X335189Y-299749D01*
X335972Y-299959D01*
X336755Y-299749D01*
X337382Y-299119D01*
X337695Y-298174D01*
Y-293659D01*
G01X341332D02*
X343212D01*
G01X342272D02*
Y-299959D01*
G01X341332D02*
X343212D01*
G01X346927Y-299119D02*
X347554Y-299644D01*
X348259Y-299959D01*
X348885D01*
X349512Y-299644D01*
X349982Y-299119D01*
X350217Y-298384D01*
X350060Y-297649D01*
X349669Y-297019D01*
X348964Y-296599D01*
X348024Y-296389D01*
X347475Y-295969D01*
X347240Y-295234D01*
X347397Y-294499D01*
X347789Y-293974D01*
X348337Y-293659D01*
X348885D01*
X349434Y-293869D01*
X349904Y-294394D01*
G01X353227Y-299959D02*
Y-293659D01*
G01X356517D02*
Y-299959D01*
G01Y-296809D02*
X353227D01*
G01X359214Y-299959D02*
X361172Y-293659D01*
X363130Y-299959D01*
G01X362425Y-297754D02*
X359919D01*
G01X365670Y-299959D02*
Y-293659D01*
X369274Y-299959D01*
Y-293659D01*
G01X378349Y-299959D02*
Y-293659D01*
X379915D01*
X380542Y-293974D01*
X381012Y-294394D01*
X381404Y-295024D01*
X381717Y-295759D01*
X381795Y-296809D01*
X381717Y-297859D01*
X381404Y-298594D01*
X381012Y-299224D01*
X380542Y-299644D01*
X379915Y-299959D01*
X378349D01*
G01X385432Y-293659D02*
X387312D01*
G01X386372D02*
Y-299959D01*
G01X385432D02*
X387312D01*
G01X391027Y-299119D02*
X391654Y-299644D01*
X392359Y-299959D01*
X392985D01*
X393612Y-299644D01*
X394082Y-299119D01*
X394317Y-298384D01*
X394160Y-297649D01*
X393769Y-297019D01*
X393064Y-296599D01*
X392124Y-296389D01*
X391575Y-295969D01*
X391340Y-295234D01*
X391497Y-294499D01*
X391889Y-293974D01*
X392437Y-293659D01*
X392985D01*
X393534Y-293869D01*
X394004Y-294394D01*
G01X398972Y-293659D02*
Y-299959D01*
G01X397170Y-293659D02*
X400774D01*
G01X405272Y-300169D02*
X405115Y-300064D01*
Y-299854D01*
X405272Y-299749D01*
X405429Y-299854D01*
Y-300064D01*
X405272Y-300169D01*
G01X411415Y-301114D02*
X411729Y-299749D01*
G01X417872Y-293659D02*
Y-299959D01*
G01X416070Y-293659D02*
X419674D01*
G01X422214Y-299959D02*
X424172Y-293659D01*
X426130Y-299959D01*
G01X425425Y-297754D02*
X422919D01*
G01X430472Y-299959D02*
X429845Y-299854D01*
X429297Y-299434D01*
X428827Y-298804D01*
X428514Y-298069D01*
X428357Y-297229D01*
Y-296389D01*
X428514Y-295549D01*
X428827Y-294814D01*
X429297Y-294184D01*
X429845Y-293764D01*
X430472Y-293659D01*
X431099Y-293764D01*
X431647Y-294184D01*
X432117Y-294814D01*
X432430Y-295549D01*
X432587Y-296389D01*
Y-297229D01*
X432430Y-298069D01*
X432117Y-298804D01*
X431647Y-299434D01*
X431099Y-299854D01*
X430472Y-299959D01*
G01X436772D02*
Y-297124D01*
X435205Y-293659D01*
G01X438339D02*
X436772Y-297124D01*
G01X441349Y-293659D02*
Y-298174D01*
X441662Y-299119D01*
X442289Y-299749D01*
X443072Y-299959D01*
X443855Y-299749D01*
X444482Y-299119D01*
X444795Y-298174D01*
Y-293659D01*
G01X447414Y-299959D02*
X449372Y-293659D01*
X451330Y-299959D01*
G01X450625Y-297754D02*
X448119D01*
G01X453870Y-299959D02*
Y-293659D01*
X457474Y-299959D01*
Y-293659D01*
G01X327870Y-289959D02*
Y-283659D01*
X331474Y-289959D01*
Y-283659D01*
G01X335972Y-289959D02*
X335345Y-289854D01*
X334797Y-289434D01*
X334327Y-288804D01*
X334014Y-288069D01*
X333857Y-287229D01*
Y-286389D01*
X334014Y-285549D01*
X334327Y-284814D01*
X334797Y-284184D01*
X335345Y-283764D01*
X335972Y-283659D01*
X336599Y-283764D01*
X337147Y-284184D01*
X337617Y-284814D01*
X337930Y-285549D01*
X338087Y-286389D01*
Y-287229D01*
X337930Y-288069D01*
X337617Y-288804D01*
X337147Y-289434D01*
X336599Y-289854D01*
X335972Y-289959D01*
G01X342272Y-290169D02*
X342115Y-290064D01*
Y-289854D01*
X342272Y-289749D01*
X342429Y-289854D01*
Y-290064D01*
X342272Y-290169D01*
G01X347084Y-284709D02*
X347554Y-284079D01*
X348102Y-283764D01*
X348729Y-283659D01*
X349512Y-283869D01*
X350060Y-284394D01*
X350217Y-285024D01*
X350139Y-285654D01*
X349825Y-286179D01*
X348259Y-287229D01*
X347554Y-287964D01*
X347084Y-289014D01*
X346927Y-289959D01*
X350217D01*
G01X354872D02*
Y-283659D01*
X353932Y-284919D01*
G01Y-289959D02*
X355812D01*
G01X361172D02*
Y-283659D01*
X360232Y-284919D01*
G01Y-289959D02*
X362112D01*
G01X367315Y-291114D02*
X367629Y-289749D01*
G01X371422Y-283659D02*
X372519Y-289959D01*
X373772Y-283659D01*
X375025Y-289959D01*
X376122Y-283659D01*
G01X381639Y-289959D02*
X378505D01*
Y-283659D01*
X381639D01*
G01X380385Y-286704D02*
X378505D01*
G01X384570Y-289959D02*
Y-283659D01*
X388174Y-289959D01*
Y-283659D01*
G01X391027Y-289959D02*
Y-283659D01*
G01X394317D02*
Y-289959D01*
G01Y-286809D02*
X391027D01*
G01X397249Y-283659D02*
Y-288174D01*
X397562Y-289119D01*
X398189Y-289749D01*
X398972Y-289959D01*
X399755Y-289749D01*
X400382Y-289119D01*
X400695Y-288174D01*
Y-283659D01*
G01X403314Y-289959D02*
X405272Y-283659D01*
X407230Y-289959D01*
G01X406525Y-287754D02*
X404019D01*
G01X416384Y-284709D02*
X416854Y-284079D01*
X417402Y-283764D01*
X418029Y-283659D01*
X418812Y-283869D01*
X419360Y-284394D01*
X419517Y-285024D01*
X419439Y-285654D01*
X419125Y-286179D01*
X417559Y-287229D01*
X416854Y-287964D01*
X416384Y-289014D01*
X416227Y-289959D01*
X419517D01*
G01X422370D02*
Y-283659D01*
X425974Y-289959D01*
Y-283659D01*
G01X428749Y-289959D02*
Y-283659D01*
X430315D01*
X430942Y-283974D01*
X431412Y-284394D01*
X431804Y-285024D01*
X432117Y-285759D01*
X432195Y-286809D01*
X432117Y-287859D01*
X431804Y-288594D01*
X431412Y-289224D01*
X430942Y-289644D01*
X430315Y-289959D01*
X428749D01*
G01X441505D02*
Y-283659D01*
X443464D01*
X444090Y-283974D01*
X444482Y-284394D01*
X444639Y-285234D01*
X444482Y-286074D01*
X444012Y-286599D01*
X443464Y-286914D01*
X441505D01*
G01X443464D02*
X444639Y-289959D01*
G01X447649D02*
Y-283659D01*
X449215D01*
X449842Y-283974D01*
X450312Y-284394D01*
X450704Y-285024D01*
X451017Y-285759D01*
X451095Y-286809D01*
X451017Y-287859D01*
X450704Y-288594D01*
X450312Y-289224D01*
X449842Y-289644D01*
X449215Y-289959D01*
X447649D01*
G01X455672Y-290169D02*
X455515Y-290064D01*
Y-289854D01*
X455672Y-289749D01*
X455829Y-289854D01*
Y-290064D01*
X455672Y-290169D01*
G01X351972Y-279259D02*
X349452Y-278842D01*
X347247Y-277176D01*
X345357Y-274676D01*
X344097Y-271759D01*
X343467Y-268426D01*
Y-265092D01*
X344097Y-261759D01*
X345357Y-258842D01*
X347247Y-256343D01*
X349452Y-254676D01*
X351972Y-254259D01*
X354492Y-254676D01*
X356697Y-256343D01*
X358587Y-258842D01*
X359847Y-261759D01*
X360477Y-265092D01*
Y-268426D01*
X359847Y-271759D01*
X358587Y-274676D01*
X356697Y-277176D01*
X354492Y-278842D01*
X351972Y-279259D01*
G01X354492Y-272592D02*
X358272Y-279259D01*
G01X371817Y-262593D02*
Y-274259D01*
X373077Y-277176D01*
X374967Y-278842D01*
X377172Y-279259D01*
X379377Y-278842D01*
X381267Y-277176D01*
X382527Y-274259D01*
G01Y-279259D02*
Y-262593D01*
G01X408042Y-279259D02*
Y-262593D01*
G01Y-265509D02*
X406782Y-263843D01*
X404892Y-263009D01*
X402687Y-262593D01*
X400482Y-263426D01*
X398592Y-265092D01*
X397332Y-267593D01*
X396702Y-270926D01*
X397332Y-274259D01*
X398592Y-276760D01*
X400482Y-278426D01*
X402687Y-279259D01*
X404892Y-278842D01*
X406782Y-277593D01*
X408042Y-275926D01*
G01X422217Y-279259D02*
Y-262593D01*
G01Y-266759D02*
X423477Y-264676D01*
X425367Y-263009D01*
X427887Y-262593D01*
X430092Y-263009D01*
X431982Y-264676D01*
X432927Y-267593D01*
Y-279259D01*
G01X452772Y-254259D02*
Y-279259D01*
G01X448362Y-262593D02*
X457182D01*
G01X483642Y-279259D02*
Y-262593D01*
G01Y-265509D02*
X482382Y-263843D01*
X480492Y-263009D01*
X478287Y-262593D01*
X476082Y-263426D01*
X474192Y-265092D01*
X472932Y-267593D01*
X472302Y-270926D01*
X472932Y-274259D01*
X474192Y-276760D01*
X476082Y-278426D01*
X478287Y-279259D01*
X480492Y-278842D01*
X482382Y-277593D01*
X483642Y-275926D01*
G01X534722Y-290893D02*
X535522Y-291559D01*
X536422Y-291959D01*
X537222D01*
X538022Y-291559D01*
X538622Y-290893D01*
X538922Y-289959D01*
X538722Y-289026D01*
X538222Y-288226D01*
X537322Y-287692D01*
X536122Y-287426D01*
X535422Y-286892D01*
X535122Y-285959D01*
X535322Y-285026D01*
X535822Y-284359D01*
X536522Y-283959D01*
X537222D01*
X537922Y-284226D01*
X538522Y-284892D01*
G01X543622Y-283959D02*
X546022D01*
G01X544822D02*
Y-291959D01*
G01X543622D02*
X546022D01*
G01X550822Y-283959D02*
Y-291959D01*
X554822D01*
G01X558622D02*
Y-283959D01*
G01X562422D02*
X558622Y-288893D01*
G01X563022Y-291959D02*
X560322Y-286626D01*
G01X567522Y-289292D02*
X570122D01*
G01X577622Y-287692D02*
X578022Y-287292D01*
X578322Y-286626D01*
X578522Y-285692D01*
X578322Y-284892D01*
X577922Y-284359D01*
X577222Y-283959D01*
X574522D01*
Y-291959D01*
X577822D01*
X578522Y-291426D01*
X578922Y-290626D01*
X579122Y-289692D01*
X578922Y-288759D01*
X578322Y-287959D01*
X577622Y-287692D01*
X574522D01*
G01X584822Y-291959D02*
X584022Y-291826D01*
X583322Y-291292D01*
X582722Y-290492D01*
X582322Y-289559D01*
X582122Y-288492D01*
Y-287426D01*
X582322Y-286359D01*
X582722Y-285426D01*
X583322Y-284626D01*
X584022Y-284092D01*
X584822Y-283959D01*
X585622Y-284092D01*
X586322Y-284626D01*
X586922Y-285426D01*
X587322Y-286359D01*
X587522Y-287426D01*
Y-288492D01*
X587322Y-289559D01*
X586922Y-290492D01*
X586322Y-291292D01*
X585622Y-291826D01*
X584822Y-291959D01*
G01X592822Y-283959D02*
Y-291959D01*
G01X590522Y-283959D02*
X595122D01*
G01X523322Y-258959D02*
Y-266959D01*
X527322D01*
G01X535122D02*
Y-261626D01*
G01Y-262559D02*
X534722Y-262026D01*
X534122Y-261759D01*
X533422Y-261626D01*
X532722Y-261892D01*
X532122Y-262426D01*
X531722Y-263226D01*
X531522Y-264292D01*
X531722Y-265359D01*
X532122Y-266159D01*
X532722Y-266692D01*
X533422Y-266959D01*
X534122Y-266826D01*
X534722Y-266426D01*
X535122Y-265893D01*
G01X539222Y-269359D02*
X539822Y-269626D01*
X540622Y-269359D01*
X541122Y-268826D01*
X541522Y-268159D01*
X542122Y-266026D01*
X543422Y-261626D01*
G01X540222D02*
X542122Y-266026D01*
G01X547822Y-263359D02*
X551022D01*
X550722Y-262426D01*
X550222Y-261892D01*
X549522Y-261626D01*
X548822Y-261759D01*
X548222Y-262159D01*
X547822Y-263092D01*
X547622Y-263893D01*
Y-264692D01*
X547822Y-265492D01*
X548322Y-266292D01*
X548922Y-266826D01*
X549622Y-266959D01*
X550322Y-266692D01*
X551022Y-265893D01*
G01X555922Y-266959D02*
Y-261626D01*
G01Y-262692D02*
X556422Y-262159D01*
X556922Y-261759D01*
X557622Y-261626D01*
X558122Y-261759D01*
X558722Y-262159D01*
G01X542022Y-316959D02*
Y-308959D01*
X546622Y-316959D01*
Y-308959D01*
G01X552322Y-311626D02*
Y-316959D01*
G01Y-309492D02*
X552122Y-309359D01*
Y-309092D01*
X552322Y-308959D01*
X552522Y-309092D01*
Y-309359D01*
X552322Y-309492D01*
G01X558622Y-316959D02*
Y-311626D01*
G01Y-312959D02*
X559022Y-312292D01*
X559622Y-311759D01*
X560422Y-311626D01*
X561122Y-311759D01*
X561722Y-312292D01*
X562022Y-313226D01*
Y-316959D01*
G01X570122D02*
Y-311626D01*
G01Y-312559D02*
X569722Y-312026D01*
X569122Y-311759D01*
X568422Y-311626D01*
X567722Y-311892D01*
X567122Y-312426D01*
X566722Y-313226D01*
X566522Y-314292D01*
X566722Y-315359D01*
X567122Y-316159D01*
X567722Y-316692D01*
X568422Y-316959D01*
X569122Y-316826D01*
X569722Y-316426D01*
X570122Y-315893D01*
G01X649922Y-310292D02*
X650522Y-309492D01*
X651222Y-309092D01*
X652022Y-308959D01*
X653022Y-309226D01*
X653722Y-309892D01*
X653922Y-310692D01*
X653822Y-311493D01*
X653422Y-312159D01*
X651422Y-313492D01*
X650522Y-314426D01*
X649922Y-315759D01*
X649722Y-316959D01*
X653922D01*
G01X659822Y-308959D02*
X659022Y-309226D01*
X658422Y-309892D01*
X658022Y-310692D01*
X657722Y-311759D01*
X657622Y-312959D01*
X657722Y-314159D01*
X658022Y-315226D01*
X658422Y-316026D01*
X659022Y-316692D01*
X659822Y-316959D01*
X660622Y-316692D01*
X661222Y-316026D01*
X661622Y-315226D01*
X661922Y-314159D01*
X662022Y-312959D01*
X661922Y-311759D01*
X661622Y-310692D01*
X661222Y-309892D01*
X660622Y-309226D01*
X659822Y-308959D01*
G01X665922Y-310292D02*
X666522Y-309492D01*
X667222Y-309092D01*
X668022Y-308959D01*
X669022Y-309226D01*
X669722Y-309892D01*
X669922Y-310692D01*
X669822Y-311493D01*
X669422Y-312159D01*
X667422Y-313492D01*
X666522Y-314426D01*
X665922Y-315759D01*
X665722Y-316959D01*
X669922D01*
G01X673922Y-310292D02*
X674522Y-309492D01*
X675222Y-309092D01*
X676022Y-308959D01*
X677022Y-309226D01*
X677722Y-309892D01*
X677922Y-310692D01*
X677822Y-311493D01*
X677422Y-312159D01*
X675422Y-313492D01*
X674522Y-314426D01*
X673922Y-315759D01*
X673722Y-316959D01*
X677922D01*
G01X682022Y-317226D02*
X685622Y-308959D01*
G01X691822Y-316959D02*
Y-308959D01*
X690622Y-310559D01*
G01Y-316959D02*
X693022D01*
G01X697922Y-310292D02*
X698522Y-309492D01*
X699222Y-309092D01*
X700022Y-308959D01*
X701022Y-309226D01*
X701722Y-309892D01*
X701922Y-310692D01*
X701822Y-311493D01*
X701422Y-312159D01*
X699422Y-313492D01*
X698522Y-314426D01*
X697922Y-315759D01*
X697722Y-316959D01*
X701922D01*
G01X706022Y-317226D02*
X709622Y-308959D01*
G01X715822D02*
X715022Y-309226D01*
X714422Y-309892D01*
X714022Y-310692D01*
X713722Y-311759D01*
X713622Y-312959D01*
X713722Y-314159D01*
X714022Y-315226D01*
X714422Y-316026D01*
X715022Y-316692D01*
X715822Y-316959D01*
X716622Y-316692D01*
X717222Y-316026D01*
X717622Y-315226D01*
X717922Y-314159D01*
X718022Y-312959D01*
X717922Y-311759D01*
X717622Y-310692D01*
X717222Y-309892D01*
X716622Y-309226D01*
X715822Y-308959D01*
G01X722122Y-316026D02*
X722822Y-316692D01*
X723622Y-316959D01*
X724422Y-316692D01*
X725122Y-315893D01*
X725622Y-314692D01*
X725822Y-313492D01*
Y-312026D01*
X725622Y-310826D01*
X725122Y-309759D01*
X724522Y-309226D01*
X723822Y-308959D01*
X723022Y-309226D01*
X722422Y-309759D01*
X722022Y-310559D01*
X721822Y-311626D01*
X722022Y-312559D01*
X722522Y-313492D01*
X723122Y-314026D01*
X723822Y-314159D01*
X724622Y-313893D01*
X725222Y-313226D01*
X725822Y-312026D01*
G01X649622Y-291959D02*
Y-283959D01*
X651622D01*
X652422Y-284359D01*
X653022Y-284892D01*
X653522Y-285692D01*
X653922Y-286626D01*
X654022Y-287959D01*
X653922Y-289292D01*
X653522Y-290226D01*
X653022Y-291026D01*
X652422Y-291559D01*
X651622Y-291959D01*
X649622D01*
G01X657322D02*
X659822Y-283959D01*
X662322Y-291959D01*
G01X661422Y-289159D02*
X658222D01*
G01X667822Y-283959D02*
X667022Y-284226D01*
X666422Y-284892D01*
X666022Y-285692D01*
X665722Y-286759D01*
X665622Y-287959D01*
X665722Y-289159D01*
X666022Y-290226D01*
X666422Y-291026D01*
X667022Y-291692D01*
X667822Y-291959D01*
X668622Y-291692D01*
X669222Y-291026D01*
X669622Y-290226D01*
X669922Y-289159D01*
X670022Y-287959D01*
X669922Y-286759D01*
X669622Y-285692D01*
X669222Y-284892D01*
X668622Y-284226D01*
X667822Y-283959D01*
G01X673922Y-291959D02*
Y-283959D01*
X677722D01*
G01X676322Y-287826D02*
X673922D01*
G01X683822Y-283959D02*
X683022Y-284226D01*
X682422Y-284892D01*
X682022Y-285692D01*
X681722Y-286759D01*
X681622Y-287959D01*
X681722Y-289159D01*
X682022Y-290226D01*
X682422Y-291026D01*
X683022Y-291692D01*
X683822Y-291959D01*
X684622Y-291692D01*
X685222Y-291026D01*
X685622Y-290226D01*
X685922Y-289159D01*
X686022Y-287959D01*
X685922Y-286759D01*
X685622Y-285692D01*
X685222Y-284892D01*
X684622Y-284226D01*
X683822Y-283959D01*
G01X691822D02*
Y-291959D01*
G01X689522Y-283959D02*
X694122D01*
G01X697922Y-291959D02*
Y-283959D01*
X701722D01*
G01X700322Y-287826D02*
X697922D01*
G01X708622Y-287692D02*
X709022Y-287292D01*
X709322Y-286626D01*
X709522Y-285692D01*
X709322Y-284892D01*
X708922Y-284359D01*
X708222Y-283959D01*
X705522D01*
Y-291959D01*
X708822D01*
X709522Y-291426D01*
X709922Y-290626D01*
X710122Y-289692D01*
X709922Y-288759D01*
X709322Y-287959D01*
X708622Y-287692D01*
X705522D01*
G01X713922Y-288626D02*
X714622Y-287692D01*
X715222Y-287159D01*
X716022Y-286892D01*
X716722Y-287159D01*
X717222Y-287692D01*
X717622Y-288492D01*
X717722Y-289426D01*
X717622Y-290226D01*
X717222Y-291026D01*
X716622Y-291692D01*
X715922Y-291959D01*
X715122Y-291692D01*
X714422Y-290893D01*
X714022Y-289692D01*
X713922Y-288359D01*
X714122Y-286626D01*
X714422Y-285692D01*
X714922Y-284759D01*
X715622Y-284092D01*
X716322Y-283959D01*
X717022Y-284226D01*
X717522Y-284892D01*
G01X721622Y-291959D02*
Y-283959D01*
X723622D01*
X724422Y-284359D01*
X725022Y-284892D01*
X725522Y-285692D01*
X725922Y-286626D01*
X726022Y-287959D01*
X725922Y-289292D01*
X725522Y-290226D01*
X725022Y-291026D01*
X724422Y-291559D01*
X723622Y-291959D01*
X721622D01*
G01X731822Y-283959D02*
X731022Y-284226D01*
X730422Y-284892D01*
X730022Y-285692D01*
X729722Y-286759D01*
X729622Y-287959D01*
X729722Y-289159D01*
X730022Y-290226D01*
X730422Y-291026D01*
X731022Y-291692D01*
X731822Y-291959D01*
X732622Y-291692D01*
X733222Y-291026D01*
X733622Y-290226D01*
X733922Y-289159D01*
X734022Y-287959D01*
X733922Y-286759D01*
X733622Y-285692D01*
X733222Y-284892D01*
X732622Y-284226D01*
X731822Y-283959D01*
G01X649862Y-270000D02*
Y-263700D01*
X652838D01*
G01X651742Y-266745D02*
X649862D01*
G01X657650Y-263700D02*
X657023Y-263910D01*
X656553Y-264435D01*
X656240Y-265065D01*
X656005Y-265905D01*
X655927Y-266850D01*
X656005Y-267795D01*
X656240Y-268635D01*
X656553Y-269265D01*
X657023Y-269790D01*
X657650Y-270000D01*
X658277Y-269790D01*
X658747Y-269265D01*
X659060Y-268635D01*
X659295Y-267795D01*
X659373Y-266850D01*
X659295Y-265905D01*
X659060Y-265065D01*
X658747Y-264435D01*
X658277Y-263910D01*
X657650Y-263700D01*
G01X663950D02*
Y-270000D01*
G01X662148Y-263700D02*
X665752D01*
G01X667900Y-272100D02*
X672600D01*
G01X674983Y-270000D02*
Y-263700D01*
X676863D01*
X677490Y-264015D01*
X677960Y-264750D01*
X678117Y-265590D01*
X677960Y-266430D01*
X677568Y-267060D01*
X676863Y-267375D01*
X674983D01*
G01X684573Y-264225D02*
X684103Y-263910D01*
X683555Y-263700D01*
X682928D01*
X682223Y-264015D01*
X681675Y-264540D01*
X681283Y-265170D01*
X680970Y-266220D01*
X680892Y-267165D01*
X681048Y-268110D01*
X681283Y-268740D01*
X681753Y-269370D01*
X682302Y-269790D01*
X682850Y-270000D01*
X683398D01*
X683947Y-269790D01*
X684417Y-269475D01*
X684808Y-269055D01*
G01X689777Y-266640D02*
X690090Y-266325D01*
X690325Y-265800D01*
X690482Y-265065D01*
X690325Y-264435D01*
X690012Y-264015D01*
X689463Y-263700D01*
X687348D01*
Y-270000D01*
X689933D01*
X690482Y-269580D01*
X690795Y-268950D01*
X690952Y-268215D01*
X690795Y-267480D01*
X690325Y-266850D01*
X689777Y-266640D01*
X687348D01*
G01X693100Y-272100D02*
X697800D01*
G01X700262Y-270000D02*
Y-263700D01*
X703238D01*
G01X702142Y-266745D02*
X700262D01*
G01X706092Y-270000D02*
X708050Y-263700D01*
X710008Y-270000D01*
G01X709303Y-267795D02*
X706797D01*
G01X712548Y-270000D02*
Y-263700D01*
X716152Y-270000D01*
Y-263700D01*
G01X718300Y-272100D02*
X723000D01*
G01X727577Y-266640D02*
X727890Y-266325D01*
X728125Y-265800D01*
X728282Y-265065D01*
X728125Y-264435D01*
X727812Y-264015D01*
X727263Y-263700D01*
X725148D01*
Y-270000D01*
X727733D01*
X728282Y-269580D01*
X728595Y-268950D01*
X728752Y-268215D01*
X728595Y-267480D01*
X728125Y-266850D01*
X727577Y-266640D01*
X725148D01*
G01X733250Y-270000D02*
X732623Y-269895D01*
X732075Y-269475D01*
X731605Y-268845D01*
X731292Y-268110D01*
X731135Y-267270D01*
Y-266430D01*
X731292Y-265590D01*
X731605Y-264855D01*
X732075Y-264225D01*
X732623Y-263805D01*
X733250Y-263700D01*
X733877Y-263805D01*
X734425Y-264225D01*
X734895Y-264855D01*
X735208Y-265590D01*
X735365Y-266430D01*
Y-267270D01*
X735208Y-268110D01*
X734895Y-268845D01*
X734425Y-269475D01*
X733877Y-269895D01*
X733250Y-270000D01*
G01X737592D02*
X739550Y-263700D01*
X741508Y-270000D01*
G01X740803Y-267795D02*
X738297D01*
G01X744283Y-270000D02*
Y-263700D01*
X746242D01*
X746868Y-264015D01*
X747260Y-264435D01*
X747417Y-265275D01*
X747260Y-266115D01*
X746790Y-266640D01*
X746242Y-266955D01*
X744283D01*
G01X746242D02*
X747417Y-270000D01*
G01X750427D02*
Y-263700D01*
X751993D01*
X752620Y-264015D01*
X753090Y-264435D01*
X753482Y-265065D01*
X753795Y-265800D01*
X753873Y-266850D01*
X753795Y-267900D01*
X753482Y-268635D01*
X753090Y-269265D01*
X752620Y-269685D01*
X751993Y-270000D01*
X750427D01*
G01X756100Y-272100D02*
X760800D01*
G01X762713Y-270000D02*
Y-263700D01*
X764750Y-268950D01*
X766787Y-263700D01*
Y-270000D01*
G01X769483D02*
Y-263700D01*
X771363D01*
X771990Y-264015D01*
X772460Y-264750D01*
X772617Y-265590D01*
X772460Y-266430D01*
X772068Y-267060D01*
X771363Y-267375D01*
X769483D01*
G01X775627Y-269055D02*
X776097Y-269580D01*
X776645Y-269895D01*
X777350Y-270000D01*
X778055Y-269790D01*
X778603Y-269370D01*
X778995Y-268635D01*
X779073Y-267795D01*
X778917Y-266955D01*
X778525Y-266430D01*
X777977Y-266010D01*
X777428Y-265905D01*
X776880Y-266010D01*
X776175Y-266430D01*
X776410Y-263700D01*
X778525D01*
G01X783650D02*
X783023Y-263910D01*
X782553Y-264435D01*
X782240Y-265065D01*
X782005Y-265905D01*
X781927Y-266850D01*
X782005Y-267795D01*
X782240Y-268635D01*
X782553Y-269265D01*
X783023Y-269790D01*
X783650Y-270000D01*
X784277Y-269790D01*
X784747Y-269265D01*
X785060Y-268635D01*
X785295Y-267795D01*
X785373Y-266850D01*
X785295Y-265905D01*
X785060Y-265065D01*
X784747Y-264435D01*
X784277Y-263910D01*
X783650Y-263700D01*
G01X790890Y-270000D02*
Y-263700D01*
X787992Y-268215D01*
X791908D01*
G01X796250Y-270000D02*
X796798Y-269895D01*
X797425Y-269580D01*
X797817Y-269055D01*
X797973Y-268320D01*
X797817Y-267585D01*
X797347Y-266955D01*
X796642Y-266640D01*
X795858D01*
X795388Y-266430D01*
X794997Y-265905D01*
X794840Y-265170D01*
X795075Y-264435D01*
X795623Y-263910D01*
X796250Y-263700D01*
X796877Y-263910D01*
X797425Y-264435D01*
X797660Y-265170D01*
X797503Y-265905D01*
X797112Y-266430D01*
X796642Y-266640D01*
X795858D01*
X795153Y-266955D01*
X794683Y-267585D01*
X794527Y-268320D01*
X794683Y-269055D01*
X795075Y-269580D01*
X795702Y-269895D01*
X796250Y-270000D01*
G01X738322Y-319959D02*
Y-311959D01*
X737122Y-313559D01*
G01Y-319959D02*
X739522D01*
G01X744422Y-316626D02*
X745122Y-315692D01*
X745722Y-315159D01*
X746522Y-314892D01*
X747222Y-315159D01*
X747722Y-315692D01*
X748122Y-316492D01*
X748222Y-317426D01*
X748122Y-318226D01*
X747722Y-319026D01*
X747122Y-319692D01*
X746422Y-319959D01*
X745622Y-319692D01*
X744922Y-318893D01*
X744522Y-317692D01*
X744422Y-316359D01*
X744622Y-314626D01*
X744922Y-313692D01*
X745422Y-312759D01*
X746122Y-312092D01*
X746822Y-311959D01*
X747522Y-312226D01*
X748022Y-312892D01*
G01X754322Y-320226D02*
X754122Y-320092D01*
Y-319826D01*
X754322Y-319692D01*
X754522Y-319826D01*
Y-320092D01*
X754322Y-320226D01*
G01X760422Y-316626D02*
X761122Y-315692D01*
X761722Y-315159D01*
X762522Y-314892D01*
X763222Y-315159D01*
X763722Y-315692D01*
X764122Y-316492D01*
X764222Y-317426D01*
X764122Y-318226D01*
X763722Y-319026D01*
X763122Y-319692D01*
X762422Y-319959D01*
X761622Y-319692D01*
X760922Y-318893D01*
X760522Y-317692D01*
X760422Y-316359D01*
X760622Y-314626D01*
X760922Y-313692D01*
X761422Y-312759D01*
X762122Y-312092D01*
X762822Y-311959D01*
X763522Y-312226D01*
X764022Y-312892D01*
G01X783322Y-319959D02*
Y-311959D01*
X782122Y-313559D01*
G01Y-319959D02*
X784522D01*
G01X791122D02*
X791322Y-318226D01*
X791622Y-316759D01*
X792022Y-315426D01*
X792522Y-313959D01*
X793322Y-311959D01*
X789322D01*
G01X799322Y-320226D02*
X799122Y-320092D01*
Y-319826D01*
X799322Y-319692D01*
X799522Y-319826D01*
Y-320092D01*
X799322Y-320226D01*
G01X805422Y-313292D02*
X806022Y-312492D01*
X806722Y-312092D01*
X807522Y-311959D01*
X808522Y-312226D01*
X809222Y-312892D01*
X809422Y-313692D01*
X809322Y-314493D01*
X808922Y-315159D01*
X806922Y-316492D01*
X806022Y-317426D01*
X805422Y-318759D01*
X805222Y-319959D01*
X809422D01*
G01X803122Y-294959D02*
Y-286959D01*
X805122D01*
X805922Y-287359D01*
X806522Y-287892D01*
X807022Y-288692D01*
X807422Y-289626D01*
X807522Y-290959D01*
X807422Y-292292D01*
X807022Y-293226D01*
X806522Y-294026D01*
X805922Y-294559D01*
X805122Y-294959D01*
X803122D01*
M02*
